FILE_TYPE = MACRO_DRAWING;
SET COLOR_WIRE YELLOW;
SET COLOR_PROP ORANGE;
SET COLOR_DOT WHITE;
SET COLOR_ARC YELLOW;
SET COLOR_BODY GREEN;
SET COLOR_NOTE PURPLE;
SET PROP_DISPLAY VALUE;
SET PAGE_NUMBER P13;
SET PATH_NUMBER P453;
FORCEADD UNIVERSAL_POWER..1
(-3450 -500);
FORCEPROP 3 LASTPIN (-3450 -550) SIG_NAME P1V8_AUX\g
J 0
(-3440 -540);
DISPLAY 0.659574 (-3440 -540);
PAINT MONO (-3440 -540);
DISPLAY INVISIBLE (-3440 -540);
FORCEPROP 1 LAST HDL_POWER P1V8_AUX
J 1
(-3425 -450);
DISPLAY 0.702128 (-3425 -450);
PAINT GREEN (-3425 -450);
FORCEPROP 1 LAST PATH I1
J 0
(-3400 -475);
DISPLAY 0.872340 (-3400 -475);
PAINT AQUA (-3400 -475);
DISPLAY INVISIBLE (-3400 -475);
FORCEPROP 2 LAST CDS_LIB logical_power
J 0
(-3450 -500);
DISPLAY INVISIBLE (-3450 -500);
FORCEADD OFFPAGE..1
(-3425 2125);
FORCEPROP 2 LAST $XR0 30 
J 0
(-3676 2125);
DISPLAY 0.638298 (-3676 2125);
PAINT MONO (-3676 2125);
FORCEPROP 2 LAST PATH I10
J 0
(-3675 2175);
DISPLAY 1.021277 (-3675 2175);
DISPLAY INVISIBLE (-3675 2175);
FORCEPROP 1 LAST COMMENT_BODY TRUE
J 0
(-3300 2025);
DISPLAY 0.872340 (-3300 2025);
PAINT PEACH (-3300 2025);
DISPLAY INVISIBLE (-3300 2025);
FORCEPROP 1 LAST OFFPAGE TRUE
J 0
(-3100 2000);
DISPLAY 0.872340 (-3100 2000);
PAINT GREEN (-3100 2000);
DISPLAY INVISIBLE (-3100 2000);
FORCEPROP 2 LAST CDS_LIB standard
J 2
(-3425 2125);
DISPLAY INVISIBLE (-3425 2125);
FORCEADD OFFPAGE..2
(4475 4325);
FORCEPROP 2 LAST $XR0 27 
J 0
(4664 4325);
DISPLAY 0.638298 (4664 4325);
PAINT MONO (4664 4325);
FORCEPROP 2 LAST $XR1 21 
J 0
(4754 4325);
DISPLAY 0.638298 (4754 4325);
PAINT MONO (4754 4325);
FORCEPROP 1 LAST COMMENT_BODY TRUE
J 0
(4430 4230);
DISPLAY 0.872340 (4430 4230);
PAINT PEACH (4430 4230);
DISPLAY INVISIBLE (4430 4230);
FORCEPROP 1 LAST OFFPAGE TRUE
J 0
(4800 4200);
DISPLAY 0.872340 (4800 4200);
PAINT GREEN (4800 4200);
DISPLAY INVISIBLE (4800 4200);
FORCEPROP 2 LAST PATH I103
J 0
(4675 4375);
DISPLAY 1.021277 (4675 4375);
DISPLAY INVISIBLE (4675 4375);
FORCEPROP 2 LAST CDS_LIB standard
J 0
(4475 4325);
DISPLAY INVISIBLE (4475 4325);
FORCEADD OFFPAGE..4
(4475 4225);
FORCEPROP 2 LAST $XR1 27 
J 0
(4751 4225);
DISPLAY 0.638298 (4751 4225);
PAINT MONO (4751 4225);
FORCEPROP 2 LAST $XR0 21 
J 0
(4661 4225);
DISPLAY 0.638298 (4661 4225);
PAINT MONO (4661 4225);
FORCEPROP 2 LAST PATH I104
J 0
(4675 4275);
DISPLAY 1.021277 (4675 4275);
DISPLAY INVISIBLE (4675 4275);
FORCEPROP 1 LAST COMMENT_BODY TRUE
J 0
(4450 4125);
DISPLAY 1.574468 (4450 4125);
PAINT PEACH (4450 4125);
DISPLAY INVISIBLE (4450 4125);
FORCEPROP 1 LAST OFFPAGE TRUE
J 0
(4800 4100);
DISPLAY 1.574468 (4800 4100);
PAINT GREEN (4800 4100);
DISPLAY INVISIBLE (4800 4100);
FORCEPROP 2 LAST CDS_LIB standard
J 0
(4475 4225);
DISPLAY INVISIBLE (4475 4225);
FORCEADD OFFPAGE..2
(4475 4275);
FORCEPROP 2 LAST $XR1 27 
J 0
(4754 4275);
DISPLAY 0.638298 (4754 4275);
PAINT MONO (4754 4275);
FORCEPROP 2 LAST $XR0 21 
J 0
(4664 4275);
DISPLAY 0.638298 (4664 4275);
PAINT MONO (4664 4275);
FORCEPROP 2 LAST PATH I105
J 0
(4675 4325);
DISPLAY 1.021277 (4675 4325);
DISPLAY INVISIBLE (4675 4325);
FORCEPROP 1 LAST COMMENT_BODY TRUE
J 0
(4430 4180);
DISPLAY 0.872340 (4430 4180);
PAINT PEACH (4430 4180);
DISPLAY INVISIBLE (4430 4180);
FORCEPROP 1 LAST OFFPAGE TRUE
J 0
(4800 4150);
DISPLAY 0.872340 (4800 4150);
PAINT GREEN (4800 4150);
DISPLAY INVISIBLE (4800 4150);
FORCEPROP 2 LAST CDS_LIB standard
J 0
(4475 4275);
DISPLAY INVISIBLE (4475 4275);
FORCEADD OFFPAGE..5
(-2975 3125);
FORCEPROP 2 LAST $XR0 49 
J 0
(-3229 3125);
DISPLAY 0.638298 (-3229 3125);
PAINT MONO (-3229 3125);
FORCEPROP 2 LAST CDS_LIB standard
J 0
(-2975 3125);
DISPLAY INVISIBLE (-2975 3125);
FORCEPROP 1 LAST OFFPAGE TRUE
J 0
(-2650 3000);
DISPLAY 0.872340 (-2650 3000);
PAINT GREEN (-2650 3000);
DISPLAY INVISIBLE (-2650 3000);
FORCEPROP 1 LAST COMMENT_BODY TRUE
J 0
(-2875 3050);
DISPLAY 0.872340 (-2875 3050);
PAINT PEACH (-2875 3050);
DISPLAY INVISIBLE (-2875 3050);
FORCEPROP 2 LAST PATH I107
J 0
(-3175 3175);
DISPLAY 1.021277 (-3175 3175);
DISPLAY INVISIBLE (-3175 3175);
FORCEADD OFFPAGE..5
R 2
(3000 2475);
FORCEPROP 2 LAST $XR0 47 
J 0
(3189 2475);
DISPLAY 0.638298 (3189 2475);
PAINT MONO (3189 2475);
FORCEPROP 2 LAST PATH I108
J 0
(3175 2550);
DISPLAY 1.021277 (3175 2550);
DISPLAY INVISIBLE (3175 2550);
FORCEPROP 1 LAST COMMENT_BODY TRUE
J 2
(2900 2400);
DISPLAY 0.872340 (2900 2400);
PAINT PEACH (2900 2400);
DISPLAY INVISIBLE (2900 2400);
FORCEPROP 1 LAST OFFPAGE TRUE
J 2
(2675 2350);
DISPLAY 0.872340 (2675 2350);
PAINT GREEN (2675 2350);
DISPLAY INVISIBLE (2675 2350);
FORCEPROP 2 LAST CDS_LIB standard
J 0
(3000 2475);
DISPLAY INVISIBLE (3000 2475);
FORCEADD OFFPAGE..5
R 2
(3000 2425);
FORCEPROP 2 LAST $XR0 47 
J 0
(3189 2425);
DISPLAY 0.638298 (3189 2425);
PAINT MONO (3189 2425);
FORCEPROP 2 LAST PATH I109
J 0
(3175 2500);
DISPLAY 1.021277 (3175 2500);
DISPLAY INVISIBLE (3175 2500);
FORCEPROP 1 LAST COMMENT_BODY TRUE
J 2
(2900 2350);
DISPLAY 0.872340 (2900 2350);
PAINT PEACH (2900 2350);
DISPLAY INVISIBLE (2900 2350);
FORCEPROP 1 LAST OFFPAGE TRUE
J 2
(2675 2300);
DISPLAY 0.872340 (2675 2300);
PAINT GREEN (2675 2300);
DISPLAY INVISIBLE (2675 2300);
FORCEPROP 2 LAST CDS_LIB standard
J 0
(3000 2425);
DISPLAY INVISIBLE (3000 2425);
FORCEADD OFFPAGE..1
(-2125 1575);
FORCEPROP 2 LAST $XR0 10 
J 0
(-2346 1575);
DISPLAY 0.638298 (-2346 1575);
PAINT MONO (-2346 1575);
FORCEPROP 2 LAST $XR1 11 
J 0
(-2436 1575);
DISPLAY 0.638298 (-2436 1575);
PAINT MONO (-2436 1575);
FORCEPROP 2 LAST PATH I11
J 0
(-2300 1625);
DISPLAY 1.021277 (-2300 1625);
DISPLAY INVISIBLE (-2300 1625);
FORCEPROP 1 LAST COMMENT_BODY TRUE
J 0
(-2000 1475);
DISPLAY 0.872340 (-2000 1475);
PAINT PEACH (-2000 1475);
DISPLAY INVISIBLE (-2000 1475);
FORCEPROP 1 LAST OFFPAGE TRUE
J 0
(-1800 1450);
DISPLAY 0.872340 (-1800 1450);
PAINT GREEN (-1800 1450);
DISPLAY INVISIBLE (-1800 1450);
FORCEPROP 2 LAST CDS_LIB standard
J 0
(-2125 1575);
DISPLAY INVISIBLE (-2125 1575);
FORCEADD OFFPAGE..5
R 2
(3000 2325);
FORCEPROP 2 LAST $XR0 47 
J 0
(3189 2325);
DISPLAY 0.638298 (3189 2325);
PAINT MONO (3189 2325);
FORCEPROP 2 LAST PATH I110
J 0
(3175 2400);
DISPLAY 1.021277 (3175 2400);
DISPLAY INVISIBLE (3175 2400);
FORCEPROP 1 LAST COMMENT_BODY TRUE
J 2
(2900 2250);
DISPLAY 0.872340 (2900 2250);
PAINT PEACH (2900 2250);
DISPLAY INVISIBLE (2900 2250);
FORCEPROP 1 LAST OFFPAGE TRUE
J 2
(2675 2200);
DISPLAY 0.872340 (2675 2200);
PAINT GREEN (2675 2200);
DISPLAY INVISIBLE (2675 2200);
FORCEPROP 2 LAST CDS_LIB standard
J 0
(3000 2325);
DISPLAY INVISIBLE (3000 2325);
FORCEADD OFFPAGE..5
R 2
(3000 2375);
FORCEPROP 2 LAST $XR0 47 
J 0
(3189 2375);
DISPLAY 0.638298 (3189 2375);
PAINT MONO (3189 2375);
FORCEPROP 2 LAST PATH I111
J 0
(3175 2450);
DISPLAY 1.021277 (3175 2450);
DISPLAY INVISIBLE (3175 2450);
FORCEPROP 1 LAST COMMENT_BODY TRUE
J 2
(2900 2300);
DISPLAY 0.872340 (2900 2300);
PAINT PEACH (2900 2300);
DISPLAY INVISIBLE (2900 2300);
FORCEPROP 1 LAST OFFPAGE TRUE
J 2
(2675 2250);
DISPLAY 0.872340 (2675 2250);
PAINT GREEN (2675 2250);
DISPLAY INVISIBLE (2675 2250);
FORCEPROP 2 LAST CDS_LIB standard
J 0
(3000 2375);
DISPLAY INVISIBLE (3000 2375);
FORCEADD OFFPAGE..5
R 2
(3000 2275);
FORCEPROP 2 LAST $XR0 47 
J 0
(3189 2275);
DISPLAY 0.638298 (3189 2275);
PAINT MONO (3189 2275);
FORCEPROP 2 LAST PATH I112
J 0
(3175 2350);
DISPLAY 1.021277 (3175 2350);
DISPLAY INVISIBLE (3175 2350);
FORCEPROP 1 LAST COMMENT_BODY TRUE
J 2
(2900 2200);
DISPLAY 0.872340 (2900 2200);
PAINT PEACH (2900 2200);
DISPLAY INVISIBLE (2900 2200);
FORCEPROP 1 LAST OFFPAGE TRUE
J 2
(2675 2150);
DISPLAY 0.872340 (2675 2150);
PAINT GREEN (2675 2150);
DISPLAY INVISIBLE (2675 2150);
FORCEPROP 2 LAST CDS_LIB standard
J 0
(3000 2275);
DISPLAY INVISIBLE (3000 2275);
FORCEADD OFFPAGE..5
R 2
(3000 2225);
FORCEPROP 2 LAST $XR0 47 
J 0
(3189 2225);
DISPLAY 0.638298 (3189 2225);
PAINT MONO (3189 2225);
FORCEPROP 2 LAST PATH I113
J 0
(3175 2300);
DISPLAY 1.021277 (3175 2300);
DISPLAY INVISIBLE (3175 2300);
FORCEPROP 1 LAST COMMENT_BODY TRUE
J 2
(2900 2150);
DISPLAY 0.872340 (2900 2150);
PAINT PEACH (2900 2150);
DISPLAY INVISIBLE (2900 2150);
FORCEPROP 1 LAST OFFPAGE TRUE
J 2
(2675 2100);
DISPLAY 0.872340 (2675 2100);
PAINT GREEN (2675 2100);
DISPLAY INVISIBLE (2675 2100);
FORCEPROP 2 LAST CDS_LIB standard
J 0
(3000 2225);
DISPLAY INVISIBLE (3000 2225);
FORCEADD OFFPAGE..5
R 2
(3000 2175);
FORCEPROP 2 LAST $XR0 47 
J 0
(3189 2175);
DISPLAY 0.638298 (3189 2175);
PAINT MONO (3189 2175);
FORCEPROP 2 LAST PATH I114
J 0
(3175 2250);
DISPLAY 1.021277 (3175 2250);
DISPLAY INVISIBLE (3175 2250);
FORCEPROP 1 LAST COMMENT_BODY TRUE
J 2
(2900 2100);
DISPLAY 0.872340 (2900 2100);
PAINT PEACH (2900 2100);
DISPLAY INVISIBLE (2900 2100);
FORCEPROP 1 LAST OFFPAGE TRUE
J 2
(2675 2050);
DISPLAY 0.872340 (2675 2050);
PAINT GREEN (2675 2050);
DISPLAY INVISIBLE (2675 2050);
FORCEPROP 2 LAST CDS_LIB standard
J 0
(3000 2175);
DISPLAY INVISIBLE (3000 2175);
FORCEADD OFFPAGE..5
R 2
(3000 2125);
FORCEPROP 2 LAST $XR0 47 
J 0
(3189 2125);
DISPLAY 0.638298 (3189 2125);
PAINT MONO (3189 2125);
FORCEPROP 2 LAST PATH I115
J 0
(3175 2200);
DISPLAY 1.021277 (3175 2200);
DISPLAY INVISIBLE (3175 2200);
FORCEPROP 1 LAST COMMENT_BODY TRUE
J 2
(2900 2050);
DISPLAY 0.872340 (2900 2050);
PAINT PEACH (2900 2050);
DISPLAY INVISIBLE (2900 2050);
FORCEPROP 1 LAST OFFPAGE TRUE
J 2
(2675 2000);
DISPLAY 0.872340 (2675 2000);
PAINT GREEN (2675 2000);
DISPLAY INVISIBLE (2675 2000);
FORCEPROP 2 LAST CDS_LIB standard
J 0
(3000 2125);
DISPLAY INVISIBLE (3000 2125);
FORCEADD OFFPAGE..1
(-2125 1675);
FORCEPROP 2 LAST $XR0 10 
J 0
(-2346 1675);
DISPLAY 0.638298 (-2346 1675);
PAINT MONO (-2346 1675);
FORCEPROP 2 LAST PATH I12
J 0
(-2300 1725);
DISPLAY 1.021277 (-2300 1725);
DISPLAY INVISIBLE (-2300 1725);
FORCEPROP 1 LAST COMMENT_BODY TRUE
J 0
(-2000 1575);
DISPLAY 0.872340 (-2000 1575);
PAINT PEACH (-2000 1575);
DISPLAY INVISIBLE (-2000 1575);
FORCEPROP 1 LAST OFFPAGE TRUE
J 0
(-1800 1550);
DISPLAY 0.872340 (-1800 1550);
PAINT GREEN (-1800 1550);
DISPLAY INVISIBLE (-1800 1550);
FORCEPROP 2 LAST CDS_LIB standard
J 0
(-2125 1675);
DISPLAY INVISIBLE (-2125 1675);
FORCEADD OFFPAGE..1
(-2125 1625);
FORCEPROP 2 LAST $XR0 10 
J 0
(-2346 1625);
DISPLAY 0.638298 (-2346 1625);
PAINT MONO (-2346 1625);
FORCEPROP 2 LAST $XR1 11 
J 0
(-2436 1625);
DISPLAY 0.638298 (-2436 1625);
PAINT MONO (-2436 1625);
FORCEPROP 2 LAST PATH I13
J 0
(-2300 1675);
DISPLAY 1.021277 (-2300 1675);
DISPLAY INVISIBLE (-2300 1675);
FORCEPROP 1 LAST COMMENT_BODY TRUE
J 0
(-2000 1525);
DISPLAY 0.872340 (-2000 1525);
PAINT PEACH (-2000 1525);
DISPLAY INVISIBLE (-2000 1525);
FORCEPROP 1 LAST OFFPAGE TRUE
J 0
(-1800 1500);
DISPLAY 0.872340 (-1800 1500);
PAINT GREEN (-1800 1500);
DISPLAY INVISIBLE (-1800 1500);
FORCEPROP 2 LAST CDS_LIB standard
J 0
(-2125 1625);
DISPLAY INVISIBLE (-2125 1625);
FORCEADD Q_RES..1
(-1825 3625);
FORCEPROP 1 LAST MATERIAL CHIP
J 0
(-1975 3625);
DISPLAY 0.510638 (-1975 3625);
PAINT SKYBLUE (-1975 3625);
FORCEPROP 1 LAST VALUE 33.2
J 0
(-1750 3625);
DISPLAY 0.510638 (-1750 3625);
PAINT SKYBLUE (-1750 3625);
FORCEPROP 2 LAST CDS_LIB pure_quanta
J 0
(-1825 3625);
DISPLAY INVISIBLE (-1825 3625);
FORCEPROP 1 LAST PATH I133
J 0
(-1875 3775);
DISPLAY 0.978723 (-1875 3775);
PAINT WHITE (-1875 3775);
DISPLAY INVISIBLE (-1875 3775);
FORCEPROP 1 LAST WATTAGE 1/16W
J 2
(-1850 3475);
DISPLAY 0.510638 (-1850 3475);
PAINT SKYBLUE (-1850 3475);
DISPLAY INVISIBLE (-1850 3475);
FORCEPROP 1 LAST PACK_TYPE 0402LF
J 0
(-1575 3475);
DISPLAY 0.510638 (-1575 3475);
PAINT SKYBLUE (-1575 3475);
DISPLAY INVISIBLE (-1575 3475);
FORCEPROP 1 LAST PART_NUMBER CS03322FB03
J 0
(-1875 3725);
DISPLAY 0.510638 (-1875 3725);
PAINT WHITE (-1875 3725);
DISPLAY INVISIBLE (-1875 3725);
FORCEPROP 1 LAST TOLERANCE 1%
J 0
(-1700 3625);
DISPLAY 0.510638 (-1700 3625);
PAINT SKYBLUE (-1700 3625);
DISPLAY INVISIBLE (-1700 3625);
FORCEPROP 1 LAST LOCATION R37
J 0
(-2100 3625);
DISPLAY 0.702128 (-2100 3625);
PAINT YELLOW (-2100 3625);
FORCEPROP 0 LAST $SEC 1
J 0
(-1875 3725);
DISPLAY 0.680851 (-1875 3725);
PAINT MONO (-1875 3725);
DISPLAY INVISIBLE (-1875 3725);
FORCEPROP 0 LAST CDS_SEC 1
J 0
(-1875 3725);
DISPLAY 1.021277 (-1875 3725);
DISPLAY INVISIBLE (-1875 3725);
FORCEPROP 1 LASTPIN (-1925 3625) $PN 1
J 0
(-1913 3637);
DISPLAY 0.808511 (-1913 3637);
PAINT WHITE (-1913 3637);
DISPLAY INVISIBLE (-1913 3637);
FORCEPROP 1 LASTPIN (-1725 3625) $PN 2
J 0
(-1763 3637);
DISPLAY 0.808511 (-1763 3637);
PAINT WHITE (-1763 3637);
DISPLAY INVISIBLE (-1763 3637);
FORCEADD OFFPAGE..5
(-1775 2725);
FORCEPROP 2 LAST $XR0 13 
J 0
(-2029 2725);
DISPLAY 0.638298 (-2029 2725);
PAINT MONO (-2029 2725);
FORCEPROP 2 LAST $XR2 35 
J 0
(-2209 2725);
DISPLAY 0.638298 (-2209 2725);
PAINT MONO (-2209 2725);
FORCEPROP 2 LAST $XR1 27 
J 0
(-2119 2725);
DISPLAY 0.638298 (-2119 2725);
PAINT MONO (-2119 2725);
FORCEPROP 2 LAST PATH I134
J 0
(-1725 2800);
DISPLAY 1.021277 (-1725 2800);
DISPLAY INVISIBLE (-1725 2800);
FORCEPROP 1 LAST COMMENT_BODY TRUE
J 0
(-1675 2650);
DISPLAY 0.872340 (-1675 2650);
PAINT PEACH (-1675 2650);
DISPLAY INVISIBLE (-1675 2650);
FORCEPROP 1 LAST OFFPAGE TRUE
J 0
(-1450 2600);
DISPLAY 0.872340 (-1450 2600);
PAINT GREEN (-1450 2600);
DISPLAY INVISIBLE (-1450 2600);
FORCEPROP 2 LAST CDS_LIB standard
J 0
(-1775 2725);
DISPLAY INVISIBLE (-1775 2725);
FORCEADD OFFPAGE..1
(-2125 1725);
FORCEPROP 2 LAST $XR0 10 
J 0
(-2346 1725);
DISPLAY 0.638298 (-2346 1725);
PAINT MONO (-2346 1725);
FORCEPROP 2 LAST PATH I14
J 0
(-2300 1775);
DISPLAY 1.021277 (-2300 1775);
DISPLAY INVISIBLE (-2300 1775);
FORCEPROP 1 LAST COMMENT_BODY TRUE
J 0
(-2000 1625);
DISPLAY 0.872340 (-2000 1625);
PAINT PEACH (-2000 1625);
DISPLAY INVISIBLE (-2000 1625);
FORCEPROP 1 LAST OFFPAGE TRUE
J 0
(-1800 1600);
DISPLAY 0.872340 (-1800 1600);
PAINT GREEN (-1800 1600);
DISPLAY INVISIBLE (-1800 1600);
FORCEPROP 2 LAST CDS_LIB standard
J 0
(-2125 1725);
DISPLAY INVISIBLE (-2125 1725);
FORCEADD OFFPAGE..2
(4475 3725);
FORCEPROP 2 LAST $XR0 44 
J 0
(4664 3725);
DISPLAY 0.638298 (4664 3725);
PAINT MONO (4664 3725);
FORCEPROP 2 LAST PATH I143
J 0
(4675 3775);
DISPLAY 1.021277 (4675 3775);
DISPLAY INVISIBLE (4675 3775);
FORCEPROP 1 LAST COMMENT_BODY TRUE
J 0
(4430 3630);
DISPLAY 0.872340 (4430 3630);
PAINT PEACH (4430 3630);
DISPLAY INVISIBLE (4430 3630);
FORCEPROP 1 LAST OFFPAGE TRUE
J 0
(4800 3600);
DISPLAY 0.872340 (4800 3600);
PAINT GREEN (4800 3600);
DISPLAY INVISIBLE (4800 3600);
FORCEPROP 2 LAST CDS_LIB standard
J 0
(4475 3725);
DISPLAY INVISIBLE (4475 3725);
FORCEADD OFFPAGE..4
(4475 3625);
FORCEPROP 2 LAST $XR0 44 
J 0
(4661 3625);
DISPLAY 0.638298 (4661 3625);
PAINT MONO (4661 3625);
FORCEPROP 1 LAST COMMENT_BODY TRUE
J 0
(4450 3525);
DISPLAY 0.872340 (4450 3525);
PAINT PEACH (4450 3525);
DISPLAY INVISIBLE (4450 3525);
FORCEPROP 1 LAST OFFPAGE TRUE
J 0
(4800 3500);
DISPLAY 0.872340 (4800 3500);
PAINT GREEN (4800 3500);
DISPLAY INVISIBLE (4800 3500);
FORCEPROP 2 LAST PATH I144
J 0
(4675 3675);
DISPLAY 1.021277 (4675 3675);
DISPLAY INVISIBLE (4675 3675);
FORCEPROP 2 LAST CDS_LIB standard
J 0
(4475 3625);
DISPLAY INVISIBLE (4475 3625);
FORCEADD OFFPAGE..2
(4475 3675);
FORCEPROP 2 LAST $XR0 44 
J 0
(4664 3675);
DISPLAY 0.638298 (4664 3675);
PAINT MONO (4664 3675);
FORCEPROP 2 LAST PATH I145
J 0
(4675 3725);
DISPLAY 1.021277 (4675 3725);
DISPLAY INVISIBLE (4675 3725);
FORCEPROP 1 LAST COMMENT_BODY TRUE
J 0
(4430 3580);
DISPLAY 0.872340 (4430 3580);
PAINT PEACH (4430 3580);
DISPLAY INVISIBLE (4430 3580);
FORCEPROP 1 LAST OFFPAGE TRUE
J 0
(4800 3550);
DISPLAY 0.872340 (4800 3550);
PAINT GREEN (4800 3550);
DISPLAY INVISIBLE (4800 3550);
FORCEPROP 2 LAST CDS_LIB standard
J 0
(4475 3675);
DISPLAY INVISIBLE (4475 3675);
FORCEADD OFFPAGE..5
R 2
(4925 2775);
FORCEPROP 2 LAST $XR1 36 
J 0
(5204 2775);
DISPLAY 0.638298 (5204 2775);
PAINT MONO (5204 2775);
FORCEPROP 2 LAST $XR0 13 
J 0
(5114 2775);
DISPLAY 0.638298 (5114 2775);
PAINT MONO (5114 2775);
FORCEPROP 2 LAST PATH I146
J 0
(5100 2850);
DISPLAY 1.021277 (5100 2850);
DISPLAY INVISIBLE (5100 2850);
FORCEPROP 1 LAST COMMENT_BODY TRUE
J 2
(4825 2700);
DISPLAY 0.872340 (4825 2700);
PAINT PEACH (4825 2700);
DISPLAY INVISIBLE (4825 2700);
FORCEPROP 1 LAST OFFPAGE TRUE
J 2
(4600 2650);
DISPLAY 0.872340 (4600 2650);
PAINT GREEN (4600 2650);
DISPLAY INVISIBLE (4600 2650);
FORCEPROP 2 LAST CDS_LIB standard
J 0
(4925 2775);
DISPLAY INVISIBLE (4925 2775);
FORCEADD OFFPAGE..1
(-1775 2625);
FORCEPROP 2 LAST $XR0 11 
J 0
(-1996 2625);
DISPLAY 0.638298 (-1996 2625);
PAINT MONO (-1996 2625);
FORCEPROP 2 LAST $XR1 35 
J 0
(-2086 2625);
DISPLAY 0.638298 (-2086 2625);
PAINT MONO (-2086 2625);
FORCEPROP 2 LAST PATH I147
J 0
(-1950 2675);
DISPLAY 1.021277 (-1950 2675);
DISPLAY INVISIBLE (-1950 2675);
FORCEPROP 1 LAST COMMENT_BODY TRUE
J 0
(-1650 2525);
DISPLAY 0.872340 (-1650 2525);
PAINT PEACH (-1650 2525);
DISPLAY INVISIBLE (-1650 2525);
FORCEPROP 1 LAST OFFPAGE TRUE
J 0
(-1450 2500);
DISPLAY 0.872340 (-1450 2500);
PAINT GREEN (-1450 2500);
DISPLAY INVISIBLE (-1450 2500);
FORCEPROP 2 LAST CDS_LIB standard
J 0
(-1775 2625);
DISPLAY INVISIBLE (-1775 2625);
FORCEADD OFFPAGE..1
(-2125 1825);
FORCEPROP 2 LAST $XR0 10 
J 0
(-2376 1825);
DISPLAY 0.638298 (-2376 1825);
PAINT MONO (-2376 1825);
FORCEPROP 2 LAST CDS_LIB standard
J 0
(-2125 1825);
DISPLAY INVISIBLE (-2125 1825);
FORCEPROP 1 LAST OFFPAGE TRUE
J 0
(-1800 1700);
DISPLAY 0.872340 (-1800 1700);
PAINT GREEN (-1800 1700);
DISPLAY INVISIBLE (-1800 1700);
FORCEPROP 1 LAST COMMENT_BODY TRUE
J 0
(-2000 1725);
DISPLAY 0.872340 (-2000 1725);
PAINT PEACH (-2000 1725);
DISPLAY INVISIBLE (-2000 1725);
FORCEPROP 2 LAST PATH I15
J 0
(-2300 1875);
DISPLAY 1.021277 (-2300 1875);
DISPLAY INVISIBLE (-2300 1875);
FORCEADD OFFPAGE..2
R 2
(-2975 3725);
FORCEPROP 2 LAST $XR0 44 
J 0
(-3229 3725);
DISPLAY 0.638298 (-3229 3725);
PAINT MONO (-3229 3725);
FORCEPROP 2 LAST PATH I153
J 0
(-3175 3775);
DISPLAY 1.021277 (-3175 3775);
DISPLAY INVISIBLE (-3175 3775);
FORCEPROP 1 LAST COMMENT_BODY TRUE
J 2
(-2930 3630);
DISPLAY 0.872340 (-2930 3630);
PAINT PEACH (-2930 3630);
DISPLAY INVISIBLE (-2930 3630);
FORCEPROP 1 LAST OFFPAGE TRUE
J 2
(-3300 3600);
DISPLAY 0.872340 (-3300 3600);
PAINT GREEN (-3300 3600);
DISPLAY INVISIBLE (-3300 3600);
FORCEPROP 2 LAST CDS_LIB standard
J 0
(-2975 3725);
DISPLAY INVISIBLE (-2975 3725);
FORCEADD Q_RES..1
(-2125 2225);
FORCEPROP 1 LAST MATERIAL CHIP
J 2
(-1800 2225);
DISPLAY 0.510638 (-1800 2225);
PAINT SKYBLUE (-1800 2225);
FORCEPROP 1 LAST VALUE 33.2
J 0
(-2000 2225);
DISPLAY 0.510638 (-2000 2225);
PAINT SKYBLUE (-2000 2225);
FORCEPROP 1 LAST TOLERANCE 1%
J 0
(-2000 2225);
DISPLAY 0.510638 (-2000 2225);
PAINT SKYBLUE (-2000 2225);
DISPLAY INVISIBLE (-2000 2225);
FORCEPROP 1 LAST PART_NUMBER CS03322FB03
J 0
(-2000 2275);
DISPLAY 0.510638 (-2000 2275);
PAINT WHITE (-2000 2275);
DISPLAY INVISIBLE (-2000 2275);
FORCEPROP 1 LAST PACK_TYPE 0402LF
J 0
(-1875 2075);
DISPLAY 0.510638 (-1875 2075);
PAINT SKYBLUE (-1875 2075);
DISPLAY INVISIBLE (-1875 2075);
FORCEPROP 1 LAST WATTAGE 1/16W
J 2
(-2150 2075);
DISPLAY 0.510638 (-2150 2075);
PAINT SKYBLUE (-2150 2075);
DISPLAY INVISIBLE (-2150 2075);
FORCEPROP 1 LAST PATH I156
J 0
(-2175 2375);
DISPLAY 0.978723 (-2175 2375);
PAINT WHITE (-2175 2375);
DISPLAY INVISIBLE (-2175 2375);
FORCEPROP 2 LAST CDS_LIB pure_quanta
J 0
(-2125 2225);
DISPLAY INVISIBLE (-2125 2225);
FORCEPROP 1 LAST LOCATION R237
J 0
(-2375 2225);
DISPLAY 0.702128 (-2375 2225);
PAINT YELLOW (-2375 2225);
FORCEPROP 1 LASTPIN (-2225 2225) $PN 1
J 0
(-2213 2237);
DISPLAY 0.808511 (-2213 2237);
PAINT WHITE (-2213 2237);
FORCEPROP 1 LASTPIN (-2025 2225) $PN 2
J 0
(-2063 2237);
DISPLAY 0.808511 (-2063 2237);
PAINT WHITE (-2063 2237);
FORCEPROP 2 LAST $SEC 1
J 0
(-2175 2425);
DISPLAY 0.680851 (-2175 2425);
PAINT MONO (-2175 2425);
DISPLAY INVISIBLE (-2175 2425);
FORCEPROP 0 LAST CDS_SEC 1
J 0
(-2175 2425);
DISPLAY 0.680851 (-2175 2425);
PAINT MONO (-2175 2425);
DISPLAY INVISIBLE (-2175 2425);
FORCEADD OFFPAGE..1
(-3425 2225);
FORCEPROP 2 LAST $XR0 10 
J 0
(-3676 2225);
DISPLAY 0.638298 (-3676 2225);
PAINT MONO (-3676 2225);
FORCEPROP 2 LAST PATH I157
J 0
(-3375 2300);
DISPLAY 1.021277 (-3375 2300);
DISPLAY INVISIBLE (-3375 2300);
FORCEPROP 1 LAST COMMENT_BODY TRUE
J 0
(-3300 2125);
DISPLAY 0.872340 (-3300 2125);
PAINT PEACH (-3300 2125);
DISPLAY INVISIBLE (-3300 2125);
FORCEPROP 1 LAST OFFPAGE TRUE
J 0
(-3100 2100);
DISPLAY 0.872340 (-3100 2100);
PAINT GREEN (-3100 2100);
DISPLAY INVISIBLE (-3100 2100);
FORCEPROP 2 LAST CDS_LIB standard
J 0
(-3425 2225);
DISPLAY INVISIBLE (-3425 2225);
FORCEADD OFFPAGE..4
R 2
(-2975 2825);
FORCEPROP 2 LAST $XR0 34 
J 0
(-3226 2825);
DISPLAY 0.638298 (-3226 2825);
PAINT MONO (-3226 2825);
FORCEPROP 1 LAST OFFPAGE TRUE
J 2
(-3300 2700);
DISPLAY 0.872340 (-3300 2700);
PAINT GREEN (-3300 2700);
DISPLAY INVISIBLE (-3300 2700);
FORCEPROP 1 LAST COMMENT_BODY TRUE
J 2
(-2950 2725);
DISPLAY 0.872340 (-2950 2725);
PAINT PEACH (-2950 2725);
DISPLAY INVISIBLE (-2950 2725);
FORCEPROP 2 LAST PATH I158
J 0
(-3175 2875);
DISPLAY 1.021277 (-3175 2875);
DISPLAY INVISIBLE (-3175 2875);
FORCEPROP 2 LAST CDS_LIB standard
J 0
(-2975 2825);
DISPLAY INVISIBLE (-2975 2825);
FORCEADD Q_RES..1
(-1775 2825);
FORCEPROP 1 LAST MATERIAL CHIP
J 0
(-1600 2825);
DISPLAY 0.510638 (-1600 2825);
PAINT SKYBLUE (-1600 2825);
FORCEPROP 1 LAST VALUE 33.2
J 0
(-1700 2825);
DISPLAY 0.510638 (-1700 2825);
PAINT SKYBLUE (-1700 2825);
FORCEPROP 1 LAST TOLERANCE 1%
J 0
(-1650 2825);
DISPLAY 0.510638 (-1650 2825);
PAINT SKYBLUE (-1650 2825);
DISPLAY INVISIBLE (-1650 2825);
FORCEPROP 1 LAST PART_NUMBER CS03322FB03
J 0
(-1650 2875);
DISPLAY 0.510638 (-1650 2875);
PAINT WHITE (-1650 2875);
DISPLAY INVISIBLE (-1650 2875);
FORCEPROP 1 LAST PACK_TYPE 0402LF
J 0
(-1525 2675);
DISPLAY 0.510638 (-1525 2675);
PAINT SKYBLUE (-1525 2675);
DISPLAY INVISIBLE (-1525 2675);
FORCEPROP 1 LAST WATTAGE 1/16W
J 2
(-1800 2675);
DISPLAY 0.510638 (-1800 2675);
PAINT SKYBLUE (-1800 2675);
DISPLAY INVISIBLE (-1800 2675);
FORCEPROP 1 LAST PATH I159
J 0
(-1825 2975);
DISPLAY 0.978723 (-1825 2975);
PAINT WHITE (-1825 2975);
DISPLAY INVISIBLE (-1825 2975);
FORCEPROP 2 LAST CDS_LIB pure_quanta
J 0
(-1775 2825);
DISPLAY INVISIBLE (-1775 2825);
FORCEPROP 1 LAST LOCATION R160
J 0
(-2050 2825);
DISPLAY 0.702128 (-2050 2825);
PAINT YELLOW (-2050 2825);
FORCEPROP 0 LAST $SEC 1
J 0
(-1825 2975);
DISPLAY INVISIBLE (-1825 2975);
FORCEPROP 0 LAST CDS_SEC 1
J 0
(-1825 2975);
DISPLAY INVISIBLE (-1825 2975);
FORCEPROP 1 LASTPIN (-1875 2825) $PN 1
J 0
(-1863 2837);
DISPLAY 0.808511 (-1863 2837);
PAINT WHITE (-1863 2837);
DISPLAY INVISIBLE (-1863 2837);
FORCEPROP 1 LASTPIN (-1675 2825) $PN 2
J 0
(-1713 2837);
DISPLAY 0.808511 (-1713 2837);
PAINT WHITE (-1713 2837);
DISPLAY INVISIBLE (-1713 2837);
FORCEADD Q_RES..1
(-2125 2025);
FORCEPROP 1 LAST MATERIAL CHIP
J 2
(-1800 2025);
DISPLAY 0.510638 (-1800 2025);
PAINT SKYBLUE (-1800 2025);
FORCEPROP 1 LAST VALUE 33.2
J 0
(-2000 2025);
DISPLAY 0.510638 (-2000 2025);
PAINT SKYBLUE (-2000 2025);
FORCEPROP 1 LAST TOLERANCE 1%
J 0
(-2000 2025);
DISPLAY 0.510638 (-2000 2025);
PAINT SKYBLUE (-2000 2025);
DISPLAY INVISIBLE (-2000 2025);
FORCEPROP 1 LAST PART_NUMBER CS03322FB03
J 0
(-2000 2075);
DISPLAY 0.510638 (-2000 2075);
PAINT WHITE (-2000 2075);
DISPLAY INVISIBLE (-2000 2075);
FORCEPROP 1 LAST PACK_TYPE 0402LF
J 0
(-1875 1875);
DISPLAY 0.510638 (-1875 1875);
PAINT SKYBLUE (-1875 1875);
DISPLAY INVISIBLE (-1875 1875);
FORCEPROP 1 LAST WATTAGE 1/16W
J 2
(-2150 1875);
DISPLAY 0.510638 (-2150 1875);
PAINT SKYBLUE (-2150 1875);
DISPLAY INVISIBLE (-2150 1875);
FORCEPROP 1 LAST PATH I16
J 0
(-2175 2175);
DISPLAY 0.978723 (-2175 2175);
PAINT WHITE (-2175 2175);
DISPLAY INVISIBLE (-2175 2175);
FORCEPROP 2 LAST CDS_LIB pure_quanta
J 0
(-2125 2025);
DISPLAY INVISIBLE (-2125 2025);
FORCEPROP 1 LAST LOCATION R158
J 0
(-2375 2025);
DISPLAY 0.702128 (-2375 2025);
PAINT YELLOW (-2375 2025);
FORCEPROP 1 LASTPIN (-2225 2025) $PN 1
J 0
(-2213 2037);
DISPLAY 0.808511 (-2213 2037);
PAINT WHITE (-2213 2037);
FORCEPROP 1 LASTPIN (-2025 2025) $PN 2
J 0
(-2063 2037);
DISPLAY 0.808511 (-2063 2037);
PAINT WHITE (-2063 2037);
FORCEPROP 2 LAST $SEC 1
J 0
(-2175 2225);
DISPLAY 0.680851 (-2175 2225);
PAINT MONO (-2175 2225);
DISPLAY INVISIBLE (-2175 2225);
FORCEPROP 0 LAST CDS_SEC 1
J 0
(-2175 2225);
DISPLAY 0.680851 (-2175 2225);
PAINT MONO (-2175 2225);
DISPLAY INVISIBLE (-2175 2225);
FORCEADD Q_RES..1
(-2125 1975);
FORCEPROP 1 LAST VALUE 33.2
J 0
(-2000 1975);
DISPLAY 0.510638 (-2000 1975);
PAINT SKYBLUE (-2000 1975);
FORCEPROP 1 LAST MATERIAL CHIP
J 2
(-1800 1975);
DISPLAY 0.510638 (-1800 1975);
PAINT SKYBLUE (-1800 1975);
FORCEPROP 1 LAST TOLERANCE 1%
J 0
(-2000 1975);
DISPLAY 0.510638 (-2000 1975);
PAINT SKYBLUE (-2000 1975);
DISPLAY INVISIBLE (-2000 1975);
FORCEPROP 1 LAST PART_NUMBER CS03322FB03
J 0
(-2000 2025);
DISPLAY 0.510638 (-2000 2025);
PAINT WHITE (-2000 2025);
DISPLAY INVISIBLE (-2000 2025);
FORCEPROP 1 LAST PACK_TYPE 0402LF
J 0
(-1875 1825);
DISPLAY 0.510638 (-1875 1825);
PAINT SKYBLUE (-1875 1825);
DISPLAY INVISIBLE (-1875 1825);
FORCEPROP 1 LAST WATTAGE 1/16W
J 2
(-2150 1825);
DISPLAY 0.510638 (-2150 1825);
PAINT SKYBLUE (-2150 1825);
DISPLAY INVISIBLE (-2150 1825);
FORCEPROP 1 LAST PATH I17
J 0
(-2175 2125);
DISPLAY 0.978723 (-2175 2125);
PAINT WHITE (-2175 2125);
DISPLAY INVISIBLE (-2175 2125);
FORCEPROP 2 LAST CDS_LIB pure_quanta
J 0
(-2125 1975);
DISPLAY INVISIBLE (-2125 1975);
FORCEPROP 1 LAST LOCATION R159
J 0
(-2375 1975);
DISPLAY 0.702128 (-2375 1975);
PAINT YELLOW (-2375 1975);
FORCEPROP 1 LASTPIN (-2225 1975) $PN 1
J 0
(-2213 1987);
DISPLAY 0.808511 (-2213 1987);
PAINT WHITE (-2213 1987);
FORCEPROP 1 LASTPIN (-2025 1975) $PN 2
J 0
(-2063 1987);
DISPLAY 0.808511 (-2063 1987);
PAINT WHITE (-2063 1987);
FORCEPROP 2 LAST $SEC 1
J 0
(-2175 2175);
DISPLAY 0.680851 (-2175 2175);
PAINT MONO (-2175 2175);
DISPLAY INVISIBLE (-2175 2175);
FORCEPROP 0 LAST CDS_SEC 1
J 0
(-2175 2175);
DISPLAY 0.680851 (-2175 2175);
PAINT MONO (-2175 2175);
DISPLAY INVISIBLE (-2175 2175);
FORCEADD Q_RES..1
(-2125 2175);
FORCEPROP 1 LAST MATERIAL CHIP
J 2
(-1800 2175);
DISPLAY 0.510638 (-1800 2175);
PAINT SKYBLUE (-1800 2175);
FORCEPROP 1 LAST VALUE 33.2
J 0
(-2000 2175);
DISPLAY 0.510638 (-2000 2175);
PAINT SKYBLUE (-2000 2175);
FORCEPROP 1 LAST TOLERANCE 1%
J 0
(-2000 2175);
DISPLAY 0.510638 (-2000 2175);
PAINT SKYBLUE (-2000 2175);
DISPLAY INVISIBLE (-2000 2175);
FORCEPROP 1 LAST PART_NUMBER CS03322FB03
J 0
(-2000 2225);
DISPLAY 0.510638 (-2000 2225);
PAINT WHITE (-2000 2225);
DISPLAY INVISIBLE (-2000 2225);
FORCEPROP 1 LAST PACK_TYPE 0402LF
J 0
(-1875 2025);
DISPLAY 0.510638 (-1875 2025);
PAINT SKYBLUE (-1875 2025);
DISPLAY INVISIBLE (-1875 2025);
FORCEPROP 1 LAST WATTAGE 1/16W
J 2
(-2150 2025);
DISPLAY 0.510638 (-2150 2025);
PAINT SKYBLUE (-2150 2025);
DISPLAY INVISIBLE (-2150 2025);
FORCEPROP 1 LAST PATH I18
J 0
(-2175 2325);
DISPLAY 0.978723 (-2175 2325);
PAINT WHITE (-2175 2325);
DISPLAY INVISIBLE (-2175 2325);
FORCEPROP 2 LAST CDS_LIB pure_quanta
J 0
(-2125 2175);
DISPLAY INVISIBLE (-2125 2175);
FORCEPROP 1 LAST LOCATION R157
J 0
(-2375 2175);
DISPLAY 0.702128 (-2375 2175);
PAINT YELLOW (-2375 2175);
FORCEPROP 1 LASTPIN (-2225 2175) $PN 1
J 0
(-2213 2187);
DISPLAY 0.808511 (-2213 2187);
PAINT WHITE (-2213 2187);
FORCEPROP 1 LASTPIN (-2025 2175) $PN 2
J 0
(-2060 2185);
DISPLAY 0.808511 (-2060 2185);
PAINT WHITE (-2060 2185);
FORCEPROP 2 LAST $SEC 1
J 0
(-2175 2375);
DISPLAY 0.680851 (-2175 2375);
PAINT MONO (-2175 2375);
DISPLAY INVISIBLE (-2175 2375);
FORCEPROP 0 LAST CDS_SEC 1
J 0
(-2175 2375);
DISPLAY 0.680851 (-2175 2375);
PAINT MONO (-2175 2375);
DISPLAY INVISIBLE (-2175 2375);
FORCEADD OFFPAGE..1
(-2975 3875);
FORCEPROP 2 LAST $XR0 13 
J 0
(-3226 3875);
DISPLAY 0.638298 (-3226 3875);
PAINT MONO (-3226 3875);
FORCEPROP 2 LAST PATH I182
J 0
(-2925 3950);
DISPLAY 1.021277 (-2925 3950);
DISPLAY INVISIBLE (-2925 3950);
FORCEPROP 1 LAST COMMENT_BODY TRUE
J 0
(-2850 3775);
DISPLAY 0.872340 (-2850 3775);
PAINT PEACH (-2850 3775);
DISPLAY INVISIBLE (-2850 3775);
FORCEPROP 1 LAST OFFPAGE TRUE
J 0
(-2650 3750);
DISPLAY 0.872340 (-2650 3750);
DISPLAY INVISIBLE (-2650 3750);
FORCEPROP 2 LAST CDS_LIB standard
J 0
(-2975 3875);
DISPLAY INVISIBLE (-2975 3875);
FORCEADD OFFPAGE..1
(-2975 3825);
FORCEPROP 2 LAST $XR0 13 
J 0
(-3226 3825);
DISPLAY 0.638298 (-3226 3825);
PAINT MONO (-3226 3825);
FORCEPROP 2 LAST PATH I183
J 0
(-2925 3900);
DISPLAY 1.021277 (-2925 3900);
DISPLAY INVISIBLE (-2925 3900);
FORCEPROP 1 LAST COMMENT_BODY TRUE
J 0
(-2850 3725);
DISPLAY 0.872340 (-2850 3725);
PAINT PEACH (-2850 3725);
DISPLAY INVISIBLE (-2850 3725);
FORCEPROP 1 LAST OFFPAGE TRUE
J 0
(-2650 3700);
DISPLAY 0.872340 (-2650 3700);
DISPLAY INVISIBLE (-2650 3700);
FORCEPROP 2 LAST CDS_LIB standard
J 0
(-2975 3825);
DISPLAY INVISIBLE (-2975 3825);
FORCEADD Q_RES..1
(2750 375);
FORCEPROP 1 LAST MATERIAL CHIP
J 0
(3125 375);
DISPLAY 0.510638 (3125 375);
PAINT SKYBLUE (3125 375);
FORCEPROP 1 LAST VALUE 4.7K
J 2
(3025 375);
DISPLAY 0.510638 (3025 375);
PAINT SKYBLUE (3025 375);
FORCEPROP 1 LAST PART_NUMBER CS24702FB06
J 0
(2700 475);
DISPLAY 0.510638 (2700 475);
PAINT WHITE (2700 475);
DISPLAY INVISIBLE (2700 475);
FORCEPROP 1 LAST PACK_TYPE 0402LF
J 0
(3000 225);
DISPLAY 0.510638 (3000 225);
PAINT SKYBLUE (3000 225);
DISPLAY INVISIBLE (3000 225);
FORCEPROP 1 LAST WATTAGE 1/16W
J 2
(2725 225);
DISPLAY 0.510638 (2725 225);
PAINT SKYBLUE (2725 225);
DISPLAY INVISIBLE (2725 225);
FORCEPROP 1 LAST PATH I184
J 0
(2700 525);
DISPLAY 0.978723 (2700 525);
PAINT WHITE (2700 525);
DISPLAY INVISIBLE (2700 525);
FORCEPROP 1 LAST TOLERANCE 1%
J 0
(2750 275);
DISPLAY 0.510638 (2750 275);
PAINT SKYBLUE (2750 275);
DISPLAY INVISIBLE (2750 275);
FORCEPROP 2 LAST CDS_LIB pure_quanta
J 0
(2750 375);
DISPLAY INVISIBLE (2750 375);
FORCEPROP 1 LAST LOCATION R238
J 2
(2600 375);
DISPLAY 0.702128 (2600 375);
PAINT YELLOW (2600 375);
FORCEPROP 0 LAST $SEC 1
J 0
(2400 425);
DISPLAY INVISIBLE (2400 425);
FORCEPROP 0 LAST CDS_SEC 1
J 0
(2400 425);
DISPLAY INVISIBLE (2400 425);
FORCEPROP 1 LASTPIN (2650 375) $PN 1
J 0
(2662 387);
DISPLAY 0.808511 (2662 387);
PAINT WHITE (2662 387);
DISPLAY INVISIBLE (2662 387);
FORCEPROP 1 LASTPIN (2850 375) $PN 2
J 0
(2812 387);
DISPLAY 0.808511 (2812 387);
PAINT WHITE (2812 387);
DISPLAY INVISIBLE (2812 387);
FORCEADD Q_RES..1
(2750 325);
FORCEPROP 1 LAST MATERIAL CHIP
J 0
(3125 325);
DISPLAY 0.510638 (3125 325);
PAINT SKYBLUE (3125 325);
FORCEPROP 1 LAST VALUE 4.7K
J 2
(3025 325);
DISPLAY 0.510638 (3025 325);
PAINT SKYBLUE (3025 325);
FORCEPROP 1 LAST PART_NUMBER CS24702FB06
J 0
(2700 425);
DISPLAY 0.510638 (2700 425);
PAINT WHITE (2700 425);
DISPLAY INVISIBLE (2700 425);
FORCEPROP 1 LAST PACK_TYPE 0402LF
J 0
(3000 175);
DISPLAY 0.510638 (3000 175);
PAINT SKYBLUE (3000 175);
DISPLAY INVISIBLE (3000 175);
FORCEPROP 1 LAST WATTAGE 1/16W
J 2
(2725 175);
DISPLAY 0.510638 (2725 175);
PAINT SKYBLUE (2725 175);
DISPLAY INVISIBLE (2725 175);
FORCEPROP 1 LAST PATH I185
J 0
(2700 475);
DISPLAY 0.978723 (2700 475);
PAINT WHITE (2700 475);
DISPLAY INVISIBLE (2700 475);
FORCEPROP 1 LAST TOLERANCE 1%
J 0
(2750 225);
DISPLAY 0.510638 (2750 225);
PAINT SKYBLUE (2750 225);
DISPLAY INVISIBLE (2750 225);
FORCEPROP 2 LAST CDS_LIB pure_quanta
J 0
(2750 325);
DISPLAY INVISIBLE (2750 325);
FORCEPROP 1 LAST LOCATION R239
J 2
(2600 325);
DISPLAY 0.702128 (2600 325);
PAINT YELLOW (2600 325);
FORCEPROP 0 LAST $SEC 1
J 0
(2400 375);
DISPLAY INVISIBLE (2400 375);
FORCEPROP 0 LAST CDS_SEC 1
J 0
(2400 375);
DISPLAY INVISIBLE (2400 375);
FORCEPROP 1 LASTPIN (2650 325) $PN 1
J 0
(2662 337);
DISPLAY 0.808511 (2662 337);
PAINT WHITE (2662 337);
DISPLAY INVISIBLE (2662 337);
FORCEPROP 1 LASTPIN (2850 325) $PN 2
J 0
(2812 337);
DISPLAY 0.808511 (2812 337);
PAINT WHITE (2812 337);
DISPLAY INVISIBLE (2812 337);
FORCEADD Q_RES..1
(2750 225);
FORCEPROP 1 LAST MATERIAL CHIP
J 0
(3125 225);
DISPLAY 0.510638 (3125 225);
PAINT SKYBLUE (3125 225);
FORCEPROP 1 LAST VALUE 4.7K
J 2
(3025 225);
DISPLAY 0.510638 (3025 225);
PAINT SKYBLUE (3025 225);
FORCEPROP 1 LAST PART_NUMBER CS24702FB06
J 0
(2700 325);
DISPLAY 0.510638 (2700 325);
PAINT WHITE (2700 325);
DISPLAY INVISIBLE (2700 325);
FORCEPROP 1 LAST PACK_TYPE 0402LF
J 0
(3000 75);
DISPLAY 0.510638 (3000 75);
PAINT SKYBLUE (3000 75);
DISPLAY INVISIBLE (3000 75);
FORCEPROP 1 LAST WATTAGE 1/16W
J 2
(2725 75);
DISPLAY 0.510638 (2725 75);
PAINT SKYBLUE (2725 75);
DISPLAY INVISIBLE (2725 75);
FORCEPROP 1 LAST PATH I186
J 0
(2700 375);
DISPLAY 0.978723 (2700 375);
PAINT WHITE (2700 375);
DISPLAY INVISIBLE (2700 375);
FORCEPROP 1 LAST TOLERANCE 1%
J 0
(2750 125);
DISPLAY 0.510638 (2750 125);
PAINT SKYBLUE (2750 125);
DISPLAY INVISIBLE (2750 125);
FORCEPROP 2 LAST CDS_LIB pure_quanta
J 0
(2750 225);
DISPLAY INVISIBLE (2750 225);
FORCEPROP 1 LAST LOCATION R241
J 2
(2600 225);
DISPLAY 0.702128 (2600 225);
PAINT YELLOW (2600 225);
FORCEPROP 0 LAST $SEC 1
J 0
(2400 275);
DISPLAY INVISIBLE (2400 275);
FORCEPROP 0 LAST CDS_SEC 1
J 0
(2400 275);
DISPLAY INVISIBLE (2400 275);
FORCEPROP 1 LASTPIN (2650 225) $PN 1
J 0
(2662 237);
DISPLAY 0.808511 (2662 237);
PAINT WHITE (2662 237);
DISPLAY INVISIBLE (2662 237);
FORCEPROP 1 LASTPIN (2850 225) $PN 2
J 0
(2812 237);
DISPLAY 0.808511 (2812 237);
PAINT WHITE (2812 237);
DISPLAY INVISIBLE (2812 237);
FORCEADD Q_RES..1
(2750 275);
FORCEPROP 1 LAST MATERIAL CHIP
J 0
(3125 275);
DISPLAY 0.510638 (3125 275);
PAINT SKYBLUE (3125 275);
FORCEPROP 1 LAST VALUE 4.7K
J 2
(3025 275);
DISPLAY 0.510638 (3025 275);
PAINT SKYBLUE (3025 275);
FORCEPROP 1 LAST PART_NUMBER CS24702FB06
J 0
(2700 375);
DISPLAY 0.510638 (2700 375);
PAINT WHITE (2700 375);
DISPLAY INVISIBLE (2700 375);
FORCEPROP 1 LAST PACK_TYPE 0402LF
J 0
(3000 125);
DISPLAY 0.510638 (3000 125);
PAINT SKYBLUE (3000 125);
DISPLAY INVISIBLE (3000 125);
FORCEPROP 1 LAST WATTAGE 1/16W
J 2
(2725 125);
DISPLAY 0.510638 (2725 125);
PAINT SKYBLUE (2725 125);
DISPLAY INVISIBLE (2725 125);
FORCEPROP 1 LAST PATH I187
J 0
(2700 425);
DISPLAY 0.978723 (2700 425);
PAINT WHITE (2700 425);
DISPLAY INVISIBLE (2700 425);
FORCEPROP 1 LAST TOLERANCE 1%
J 0
(2750 175);
DISPLAY 0.510638 (2750 175);
PAINT SKYBLUE (2750 175);
DISPLAY INVISIBLE (2750 175);
FORCEPROP 2 LAST CDS_LIB pure_quanta
J 0
(2750 275);
DISPLAY INVISIBLE (2750 275);
FORCEPROP 1 LAST LOCATION R240
J 2
(2600 275);
DISPLAY 0.702128 (2600 275);
PAINT YELLOW (2600 275);
FORCEPROP 0 LAST $SEC 1
J 0
(2400 325);
DISPLAY INVISIBLE (2400 325);
FORCEPROP 0 LAST CDS_SEC 1
J 0
(2400 325);
DISPLAY INVISIBLE (2400 325);
FORCEPROP 1 LASTPIN (2650 275) $PN 1
J 0
(2662 287);
DISPLAY 0.808511 (2662 287);
PAINT WHITE (2662 287);
DISPLAY INVISIBLE (2662 287);
FORCEPROP 1 LASTPIN (2850 275) $PN 2
J 0
(2812 287);
DISPLAY 0.808511 (2812 287);
PAINT WHITE (2812 287);
DISPLAY INVISIBLE (2812 287);
FORCEADD Q_RES..1
(2750 175);
FORCEPROP 1 LAST VALUE 4.7K
J 2
(3025 175);
DISPLAY 0.510638 (3025 175);
PAINT SKYBLUE (3025 175);
FORCEPROP 1 LAST MATERIAL CHIP
J 0
(3125 175);
DISPLAY 0.510638 (3125 175);
PAINT SKYBLUE (3125 175);
FORCEPROP 1 LAST PART_NUMBER CS24702FB06
J 0
(2700 275);
DISPLAY 0.510638 (2700 275);
PAINT WHITE (2700 275);
DISPLAY INVISIBLE (2700 275);
FORCEPROP 1 LAST PACK_TYPE 0402LF
J 0
(3000 25);
DISPLAY 0.510638 (3000 25);
PAINT SKYBLUE (3000 25);
DISPLAY INVISIBLE (3000 25);
FORCEPROP 1 LAST WATTAGE 1/16W
J 2
(2725 25);
DISPLAY 0.510638 (2725 25);
PAINT SKYBLUE (2725 25);
DISPLAY INVISIBLE (2725 25);
FORCEPROP 1 LAST PATH I188
J 0
(2700 325);
DISPLAY 0.978723 (2700 325);
PAINT WHITE (2700 325);
DISPLAY INVISIBLE (2700 325);
FORCEPROP 1 LAST TOLERANCE 1%
J 0
(2750 75);
DISPLAY 0.510638 (2750 75);
PAINT SKYBLUE (2750 75);
DISPLAY INVISIBLE (2750 75);
FORCEPROP 2 LAST CDS_LIB pure_quanta
J 0
(2750 175);
DISPLAY INVISIBLE (2750 175);
FORCEPROP 1 LAST LOCATION R683
J 2
(2600 175);
DISPLAY 0.702128 (2600 175);
PAINT YELLOW (2600 175);
FORCEPROP 0 LAST $SEC 1
J 0
(2400 225);
DISPLAY INVISIBLE (2400 225);
FORCEPROP 0 LAST CDS_SEC 1
J 0
(2400 225);
DISPLAY INVISIBLE (2400 225);
FORCEPROP 1 LASTPIN (2650 175) $PN 1
J 0
(2662 187);
DISPLAY 0.808511 (2662 187);
PAINT WHITE (2662 187);
DISPLAY INVISIBLE (2662 187);
FORCEPROP 1 LASTPIN (2850 175) $PN 2
J 0
(2812 187);
DISPLAY 0.808511 (2812 187);
PAINT WHITE (2812 187);
DISPLAY INVISIBLE (2812 187);
FORCEADD OFFPAGE..2
(4100 375);
FORCEPROP 2 LAST $XR1 46 
J 0
(4379 375);
DISPLAY 0.638298 (4379 375);
PAINT MONO (4379 375);
FORCEPROP 2 LAST $XR0 13 
J 0
(4289 375);
DISPLAY 0.638298 (4289 375);
PAINT MONO (4289 375);
FORCEPROP 2 LAST PATH I189
J 0
(4275 450);
DISPLAY 1.021277 (4275 450);
DISPLAY INVISIBLE (4275 450);
FORCEPROP 1 LAST COMMENT_BODY TRUE
J 0
(4055 280);
DISPLAY 0.872340 (4055 280);
PAINT PEACH (4055 280);
DISPLAY INVISIBLE (4055 280);
FORCEPROP 1 LAST OFFPAGE TRUE
J 0
(4425 250);
DISPLAY 0.872340 (4425 250);
PAINT GREEN (4425 250);
DISPLAY INVISIBLE (4425 250);
FORCEPROP 2 LAST CDS_LIB standard
J 0
(4100 375);
DISPLAY INVISIBLE (4100 375);
FORCEADD OFFPAGE..2
(4100 325);
FORCEPROP 2 LAST $XR0 13 
J 0
(4289 325);
DISPLAY 0.638298 (4289 325);
PAINT MONO (4289 325);
FORCEPROP 2 LAST PATH I190
J 0
(4275 400);
DISPLAY 1.021277 (4275 400);
DISPLAY INVISIBLE (4275 400);
FORCEPROP 1 LAST COMMENT_BODY TRUE
J 0
(4055 230);
DISPLAY 0.872340 (4055 230);
PAINT PEACH (4055 230);
DISPLAY INVISIBLE (4055 230);
FORCEPROP 1 LAST OFFPAGE TRUE
J 0
(4425 200);
DISPLAY 0.872340 (4425 200);
PAINT GREEN (4425 200);
DISPLAY INVISIBLE (4425 200);
FORCEPROP 2 LAST CDS_LIB standard
J 0
(4100 325);
DISPLAY INVISIBLE (4100 325);
FORCEADD OFFPAGE..2
(4100 275);
FORCEPROP 2 LAST $XR0 13 
J 0
(4289 275);
DISPLAY 0.638298 (4289 275);
PAINT MONO (4289 275);
FORCEPROP 2 LAST PATH I191
J 0
(4275 350);
DISPLAY 1.021277 (4275 350);
DISPLAY INVISIBLE (4275 350);
FORCEPROP 1 LAST COMMENT_BODY TRUE
J 0
(4055 180);
DISPLAY 0.872340 (4055 180);
PAINT PEACH (4055 180);
DISPLAY INVISIBLE (4055 180);
FORCEPROP 1 LAST OFFPAGE TRUE
J 0
(4425 150);
DISPLAY 0.872340 (4425 150);
PAINT GREEN (4425 150);
DISPLAY INVISIBLE (4425 150);
FORCEPROP 2 LAST CDS_LIB standard
J 0
(4100 275);
DISPLAY INVISIBLE (4100 275);
FORCEADD OFFPAGE..2
(4100 225);
FORCEPROP 2 LAST $XR0 13 
J 0
(4289 225);
DISPLAY 0.638298 (4289 225);
PAINT MONO (4289 225);
FORCEPROP 2 LAST PATH I192
J 0
(4275 300);
DISPLAY 1.021277 (4275 300);
DISPLAY INVISIBLE (4275 300);
FORCEPROP 1 LAST COMMENT_BODY TRUE
J 0
(4055 130);
DISPLAY 0.872340 (4055 130);
PAINT PEACH (4055 130);
DISPLAY INVISIBLE (4055 130);
FORCEPROP 1 LAST OFFPAGE TRUE
J 0
(4425 100);
DISPLAY 0.872340 (4425 100);
PAINT GREEN (4425 100);
DISPLAY INVISIBLE (4425 100);
FORCEPROP 2 LAST CDS_LIB standard
J 0
(4100 225);
DISPLAY INVISIBLE (4100 225);
FORCEADD OFFPAGE..2
(4100 175);
FORCEPROP 2 LAST $XR0 13 
J 0
(4289 175);
DISPLAY 0.638298 (4289 175);
PAINT MONO (4289 175);
FORCEPROP 2 LAST PATH I193
J 0
(4275 250);
DISPLAY 1.021277 (4275 250);
DISPLAY INVISIBLE (4275 250);
FORCEPROP 1 LAST COMMENT_BODY TRUE
J 0
(4055 80);
DISPLAY 0.872340 (4055 80);
PAINT PEACH (4055 80);
DISPLAY INVISIBLE (4055 80);
FORCEPROP 1 LAST OFFPAGE TRUE
J 0
(4425 50);
DISPLAY 0.872340 (4425 50);
PAINT GREEN (4425 50);
DISPLAY INVISIBLE (4425 50);
FORCEPROP 2 LAST CDS_LIB standard
J 0
(4100 175);
DISPLAY INVISIBLE (4100 175);
FORCEADD UNIVERSAL_POWER..1
(2425 625);
FORCEPROP 3 LASTPIN (2425 575) SIG_NAME P3V3_AUX\g
J 0
(2435 585);
DISPLAY 0.659574 (2435 585);
PAINT MONO (2435 585);
DISPLAY INVISIBLE (2435 585);
FORCEPROP 1 LAST HDL_POWER P3V3_AUX
J 1
(2425 675);
DISPLAY 0.702128 (2425 675);
PAINT GREEN (2425 675);
FORCEPROP 1 LAST PATH I194
J 0
(2475 650);
DISPLAY 0.872340 (2475 650);
PAINT AQUA (2475 650);
DISPLAY INVISIBLE (2475 650);
FORCEPROP 2 LAST CDS_LIB logical_power
J 0
(2425 625);
DISPLAY INVISIBLE (2425 625);
FORCEADD Q_RES..1
(-2125 2125);
FORCEPROP 1 LAST MATERIAL CHIP
J 2
(-1800 2125);
DISPLAY 0.510638 (-1800 2125);
PAINT SKYBLUE (-1800 2125);
FORCEPROP 1 LAST VALUE 33.2
J 0
(-2000 2125);
DISPLAY 0.510638 (-2000 2125);
PAINT SKYBLUE (-2000 2125);
FORCEPROP 1 LAST TOLERANCE 1%
J 0
(-2000 2125);
DISPLAY 0.510638 (-2000 2125);
PAINT SKYBLUE (-2000 2125);
DISPLAY INVISIBLE (-2000 2125);
FORCEPROP 1 LAST PART_NUMBER CS03322FB03
J 0
(-2000 2175);
DISPLAY 0.510638 (-2000 2175);
PAINT WHITE (-2000 2175);
DISPLAY INVISIBLE (-2000 2175);
FORCEPROP 1 LAST PACK_TYPE 0402LF
J 0
(-1875 1975);
DISPLAY 0.510638 (-1875 1975);
PAINT SKYBLUE (-1875 1975);
DISPLAY INVISIBLE (-1875 1975);
FORCEPROP 1 LAST WATTAGE 1/16W
J 2
(-2150 1975);
DISPLAY 0.510638 (-2150 1975);
PAINT SKYBLUE (-2150 1975);
DISPLAY INVISIBLE (-2150 1975);
FORCEPROP 1 LAST PATH I198
J 0
(-2175 2275);
DISPLAY 0.978723 (-2175 2275);
PAINT WHITE (-2175 2275);
DISPLAY INVISIBLE (-2175 2275);
FORCEPROP 2 LAST CDS_LIB pure_quanta
J 0
(-2125 2125);
DISPLAY INVISIBLE (-2125 2125);
FORCEPROP 1 LAST LOCATION R427
J 0
(-2375 2125);
DISPLAY 0.702128 (-2375 2125);
PAINT YELLOW (-2375 2125);
FORCEPROP 1 LASTPIN (-2225 2125) $PN 1
J 0
(-2213 2137);
DISPLAY 0.808511 (-2213 2137);
PAINT WHITE (-2213 2137);
FORCEPROP 1 LASTPIN (-2025 2125) $PN 2
J 0
(-2060 2135);
DISPLAY 0.808511 (-2060 2135);
PAINT WHITE (-2060 2135);
FORCEPROP 2 LAST $SEC 1
J 0
(-2175 2325);
DISPLAY 0.680851 (-2175 2325);
PAINT MONO (-2175 2325);
DISPLAY INVISIBLE (-2175 2325);
FORCEPROP 0 LAST CDS_SEC 1
J 0
(-2175 2325);
DISPLAY 0.680851 (-2175 2325);
PAINT MONO (-2175 2325);
DISPLAY INVISIBLE (-2175 2325);
FORCEADD OFFPAGE..5
R 2
(4100 75);
FORCEPROP 2 LAST $XR1 36 
J 0
(4379 75);
DISPLAY 0.638298 (4379 75);
PAINT MONO (4379 75);
FORCEPROP 2 LAST $XR0 13 
J 0
(4289 75);
DISPLAY 0.638298 (4289 75);
PAINT MONO (4289 75);
FORCEPROP 2 LAST PATH I199
J 0
(4300 125);
DISPLAY 1.021277 (4300 125);
DISPLAY INVISIBLE (4300 125);
FORCEPROP 1 LAST COMMENT_BODY TRUE
J 2
(4000 0);
DISPLAY 0.872340 (4000 0);
PAINT PEACH (4000 0);
DISPLAY INVISIBLE (4000 0);
FORCEPROP 1 LAST OFFPAGE TRUE
J 2
(3775 -50);
DISPLAY 0.872340 (3775 -50);
PAINT GREEN (3775 -50);
DISPLAY INVISIBLE (3775 -50);
FORCEPROP 2 LAST CDS_LIB standard
J 0
(4100 75);
DISPLAY INVISIBLE (4100 75);
FORCEADD UNIVERSAL_POWER..1
(-3375 -150);
FORCEPROP 3 LASTPIN (-3375 -200) SIG_NAME P2V5_AUX\g
J 0
(-3365 -190);
DISPLAY 0.659574 (-3365 -190);
PAINT MONO (-3365 -190);
DISPLAY INVISIBLE (-3365 -190);
FORCEPROP 1 LAST HDL_POWER P2V5_AUX
J 1
(-3350 -100);
DISPLAY 0.702128 (-3350 -100);
PAINT GREEN (-3350 -100);
FORCEPROP 1 LAST PATH I2
J 0
(-3325 -125);
DISPLAY 0.872340 (-3325 -125);
PAINT AQUA (-3325 -125);
DISPLAY INVISIBLE (-3325 -125);
FORCEPROP 2 LAST CDS_LIB logical_power
J 0
(-3375 -150);
DISPLAY INVISIBLE (-3375 -150);
FORCEADD Q_RES..1
(2750 75);
FORCEPROP 1 LAST VALUE 4.7K
J 2
(3025 75);
DISPLAY 0.510638 (3025 75);
PAINT SKYBLUE (3025 75);
FORCEPROP 1 LAST MATERIAL CHIP
J 0
(3125 75);
DISPLAY 0.510638 (3125 75);
PAINT SKYBLUE (3125 75);
FORCEPROP 1 LAST PART_NUMBER CS24702FB06
J 0
(2700 175);
DISPLAY 0.510638 (2700 175);
PAINT WHITE (2700 175);
DISPLAY INVISIBLE (2700 175);
FORCEPROP 1 LAST PACK_TYPE 0402LF
J 0
(3000 -75);
DISPLAY 0.510638 (3000 -75);
PAINT SKYBLUE (3000 -75);
DISPLAY INVISIBLE (3000 -75);
FORCEPROP 1 LAST WATTAGE 1/16W
J 2
(2725 -75);
DISPLAY 0.510638 (2725 -75);
PAINT SKYBLUE (2725 -75);
DISPLAY INVISIBLE (2725 -75);
FORCEPROP 1 LAST PATH I200
J 0
(2700 225);
DISPLAY 0.978723 (2700 225);
PAINT WHITE (2700 225);
DISPLAY INVISIBLE (2700 225);
FORCEPROP 2 LAST CDS_LIB pure_quanta
J 0
(2750 75);
DISPLAY INVISIBLE (2750 75);
FORCEPROP 1 LAST TOLERANCE 1%
J 0
(2750 -25);
DISPLAY 0.510638 (2750 -25);
PAINT SKYBLUE (2750 -25);
DISPLAY INVISIBLE (2750 -25);
FORCEPROP 1 LAST LOCATION R38
J 2
(2600 75);
DISPLAY 0.702128 (2600 75);
PAINT YELLOW (2600 75);
FORCEPROP 0 LAST $SEC 1
J 0
(2400 125);
DISPLAY INVISIBLE (2400 125);
FORCEPROP 0 LAST CDS_SEC 1
J 0
(2400 125);
DISPLAY INVISIBLE (2400 125);
FORCEPROP 1 LASTPIN (2650 75) $PN 1
J 0
(2662 87);
DISPLAY 0.808511 (2662 87);
PAINT WHITE (2662 87);
DISPLAY INVISIBLE (2662 87);
FORCEPROP 1 LASTPIN (2850 75) $PN 2
J 0
(2812 87);
DISPLAY 0.808511 (2812 87);
PAINT WHITE (2812 87);
DISPLAY INVISIBLE (2812 87);
FORCEADD OFFPAGE..2
(4925 2575);
FORCEPROP 2 LAST $XR1 34 
J 0
(5204 2575);
DISPLAY 0.638298 (5204 2575);
PAINT MONO (5204 2575);
FORCEPROP 2 LAST $XR0 13 
J 0
(5114 2575);
DISPLAY 0.638298 (5114 2575);
PAINT MONO (5114 2575);
FORCEPROP 1 LAST COMMENT_BODY TRUE
J 0
(4880 2480);
DISPLAY 0.872340 (4880 2480);
PAINT GREEN (4880 2480);
DISPLAY INVISIBLE (4880 2480);
FORCEPROP 1 LAST OFFPAGE TRUE
J 0
(5250 2450);
DISPLAY 0.872340 (5250 2450);
DISPLAY INVISIBLE (5250 2450);
FORCEPROP 2 LAST PATH I202
J 0
(5125 2625);
DISPLAY 1.021277 (5125 2625);
DISPLAY INVISIBLE (5125 2625);
FORCEPROP 2 LAST CDS_LIB standard
J 0
(4925 2575);
DISPLAY INVISIBLE (4925 2575);
FORCEADD OFFPAGE..1
(-1775 2475);
FORCEPROP 2 LAST $XR0 35 
J 0
(-1996 2475);
DISPLAY 0.638298 (-1996 2475);
PAINT MONO (-1996 2475);
FORCEPROP 2 LAST PATH I203
J 0
(-1975 2525);
DISPLAY 1.021277 (-1975 2525);
DISPLAY INVISIBLE (-1975 2525);
FORCEPROP 1 LAST COMMENT_BODY TRUE
J 0
(-1650 2375);
DISPLAY 0.872340 (-1650 2375);
PAINT PEACH (-1650 2375);
DISPLAY INVISIBLE (-1650 2375);
FORCEPROP 1 LAST OFFPAGE TRUE
J 0
(-1450 2350);
DISPLAY 0.872340 (-1450 2350);
PAINT GREEN (-1450 2350);
DISPLAY INVISIBLE (-1450 2350);
FORCEPROP 2 LAST CDS_LIB standard
J 0
(-1775 2475);
DISPLAY INVISIBLE (-1775 2475);
FORCEADD Q_RES..1
(2750 25);
FORCEPROP 1 LAST VALUE 4.7K
J 2
(3025 25);
DISPLAY 0.510638 (3025 25);
PAINT SKYBLUE (3025 25);
FORCEPROP 1 LAST MATERIAL CHIP
J 0
(3125 25);
DISPLAY 0.510638 (3125 25);
PAINT SKYBLUE (3125 25);
FORCEPROP 1 LAST PART_NUMBER CS24702FB06
J 0
(2700 125);
DISPLAY 0.510638 (2700 125);
PAINT WHITE (2700 125);
DISPLAY INVISIBLE (2700 125);
FORCEPROP 1 LAST PACK_TYPE 0402LF
J 0
(3000 -125);
DISPLAY 0.510638 (3000 -125);
PAINT SKYBLUE (3000 -125);
DISPLAY INVISIBLE (3000 -125);
FORCEPROP 1 LAST WATTAGE 1/16W
J 2
(2725 -125);
DISPLAY 0.510638 (2725 -125);
PAINT SKYBLUE (2725 -125);
DISPLAY INVISIBLE (2725 -125);
FORCEPROP 1 LAST PATH I204
J 0
(2700 175);
DISPLAY 0.978723 (2700 175);
PAINT WHITE (2700 175);
DISPLAY INVISIBLE (2700 175);
FORCEPROP 1 LAST TOLERANCE 1%
J 0
(2750 -75);
DISPLAY 0.510638 (2750 -75);
PAINT SKYBLUE (2750 -75);
DISPLAY INVISIBLE (2750 -75);
FORCEPROP 2 LAST CDS_LIB pure_quanta
J 0
(2750 25);
DISPLAY INVISIBLE (2750 25);
FORCEPROP 1 LAST LOCATION R61
J 2
(2600 25);
DISPLAY 0.702128 (2600 25);
PAINT YELLOW (2600 25);
FORCEPROP 0 LAST $SEC 1
J 0
(2400 75);
DISPLAY INVISIBLE (2400 75);
FORCEPROP 0 LAST CDS_SEC 1
J 0
(2400 75);
DISPLAY INVISIBLE (2400 75);
FORCEPROP 1 LASTPIN (2650 25) $PN 1
J 0
(2662 37);
DISPLAY 0.808511 (2662 37);
PAINT WHITE (2662 37);
DISPLAY INVISIBLE (2662 37);
FORCEPROP 1 LASTPIN (2850 25) $PN 2
J 0
(2812 37);
DISPLAY 0.808511 (2812 37);
PAINT WHITE (2812 37);
DISPLAY INVISIBLE (2812 37);
FORCEADD OFFPAGE..2
(4100 25);
FORCEPROP 2 LAST $XR1 34 
J 0
(4379 25);
DISPLAY 0.638298 (4379 25);
PAINT MONO (4379 25);
FORCEPROP 2 LAST $XR0 13 
J 0
(4289 25);
DISPLAY 0.638298 (4289 25);
PAINT MONO (4289 25);
FORCEPROP 2 LAST PATH I205
J 0
(4300 75);
DISPLAY 1.021277 (4300 75);
DISPLAY INVISIBLE (4300 75);
FORCEPROP 1 LAST COMMENT_BODY TRUE
J 0
(4055 -70);
DISPLAY 0.872340 (4055 -70);
PAINT PEACH (4055 -70);
DISPLAY INVISIBLE (4055 -70);
FORCEPROP 1 LAST OFFPAGE TRUE
J 0
(4425 -100);
DISPLAY 0.872340 (4425 -100);
PAINT GREEN (4425 -100);
DISPLAY INVISIBLE (4425 -100);
FORCEPROP 2 LAST CDS_LIB standard
J 0
(4100 25);
DISPLAY INVISIBLE (4100 25);
FORCEADD OFFPAGE..3
(4475 3575);
FORCEPROP 2 LAST $XR0 44 
J 0
(4689 3575);
DISPLAY 0.638298 (4689 3575);
PAINT MONO (4689 3575);
FORCEPROP 2 LAST PATH I207
J 0
(4675 3650);
DISPLAY 1.021277 (4675 3650);
DISPLAY INVISIBLE (4675 3650);
FORCEPROP 1 LAST COMMENT_BODY TRUE
J 0
(4425 3475);
DISPLAY 0.872340 (4425 3475);
PAINT PEACH (4425 3475);
DISPLAY INVISIBLE (4425 3475);
FORCEPROP 1 LAST OFFPAGE TRUE
J 0
(4800 3450);
DISPLAY 0.872340 (4800 3450);
PAINT GREEN (4800 3450);
DISPLAY INVISIBLE (4800 3450);
FORCEPROP 2 LAST CDS_LIB standard
J 0
(4475 3575);
DISPLAY INVISIBLE (4475 3575);
FORCEADD Q_RES..1
(2875 1975);
FORCEPROP 1 LAST VALUE 33.2
J 0
(3000 1975);
DISPLAY 0.510638 (3000 1975);
PAINT SKYBLUE (3000 1975);
FORCEPROP 1 LAST MATERIAL CHIP
J 0
(3100 1975);
DISPLAY 0.510638 (3100 1975);
PAINT SKYBLUE (3100 1975);
FORCEPROP 1 LAST TOLERANCE 1%
J 0
(3000 1975);
DISPLAY 0.510638 (3000 1975);
PAINT SKYBLUE (3000 1975);
DISPLAY INVISIBLE (3000 1975);
FORCEPROP 1 LAST PART_NUMBER CS03322FB03
J 0
(2825 2075);
DISPLAY 0.510638 (2825 2075);
PAINT WHITE (2825 2075);
DISPLAY INVISIBLE (2825 2075);
FORCEPROP 1 LAST PACK_TYPE 0402LF
J 0
(3125 1825);
DISPLAY 0.510638 (3125 1825);
PAINT SKYBLUE (3125 1825);
DISPLAY INVISIBLE (3125 1825);
FORCEPROP 1 LAST WATTAGE 1/16W
J 2
(2850 1825);
DISPLAY 0.510638 (2850 1825);
PAINT SKYBLUE (2850 1825);
DISPLAY INVISIBLE (2850 1825);
FORCEPROP 1 LAST PATH I208
J 0
(2825 2125);
DISPLAY 0.978723 (2825 2125);
PAINT WHITE (2825 2125);
DISPLAY INVISIBLE (2825 2125);
FORCEPROP 2 LAST CDS_LIB pure_quanta
J 0
(2875 1975);
DISPLAY INVISIBLE (2875 1975);
FORCEPROP 1 LAST LOCATION R759
J 0
(2675 1975);
DISPLAY 0.702128 (2675 1975);
PAINT YELLOW (2675 1975);
FORCEPROP 1 LASTPIN (2775 1975) $PN 1
J 0
(2787 1987);
DISPLAY 0.808511 (2787 1987);
PAINT WHITE (2787 1987);
FORCEPROP 1 LASTPIN (2975 1975) $PN 2
J 0
(2937 1987);
DISPLAY 0.808511 (2937 1987);
PAINT WHITE (2937 1987);
FORCEPROP 2 LAST $SEC 1
J 0
(2825 2175);
DISPLAY 0.680851 (2825 2175);
PAINT MONO (2825 2175);
DISPLAY INVISIBLE (2825 2175);
FORCEPROP 0 LAST CDS_SEC 1
J 0
(2825 2175);
DISPLAY 0.680851 (2825 2175);
PAINT MONO (2825 2175);
DISPLAY INVISIBLE (2825 2175);
FORCEADD OFFPAGE..1
(-2975 2875);
FORCEPROP 2 LAST $XR0 13 
J 0
(-3226 2875);
DISPLAY 0.638298 (-3226 2875);
PAINT MONO (-3226 2875);
FORCEPROP 2 LAST $XR2 28 
J 0
(-3406 2875);
DISPLAY 0.638298 (-3406 2875);
PAINT MONO (-3406 2875);
FORCEPROP 2 LAST $XR1 35 
J 0
(-3316 2875);
DISPLAY 0.638298 (-3316 2875);
PAINT MONO (-3316 2875);
FORCEPROP 2 LAST PATH I209
J 0
(-3175 2925);
DISPLAY 1.021277 (-3175 2925);
DISPLAY INVISIBLE (-3175 2925);
FORCEPROP 1 LAST COMMENT_BODY TRUE
J 0
(-2850 2775);
DISPLAY 0.872340 (-2850 2775);
PAINT PEACH (-2850 2775);
DISPLAY INVISIBLE (-2850 2775);
FORCEPROP 1 LAST OFFPAGE TRUE
J 0
(-2650 2750);
DISPLAY 0.872340 (-2650 2750);
PAINT GREEN (-2650 2750);
DISPLAY INVISIBLE (-2650 2750);
FORCEPROP 2 LAST CDS_LIB standard
J 0
(-2975 2875);
DISPLAY INVISIBLE (-2975 2875);
FORCEADD OFFPAGE..2
(4100 -25);
FORCEPROP 2 LAST $XR2 28 
J 0
(4469 -25);
DISPLAY 0.638298 (4469 -25);
PAINT MONO (4469 -25);
FORCEPROP 2 LAST $XR1 13 
J 0
(4379 -25);
DISPLAY 0.638298 (4379 -25);
PAINT MONO (4379 -25);
FORCEPROP 2 LAST $XR0 35 
J 0
(4289 -25);
DISPLAY 0.638298 (4289 -25);
PAINT MONO (4289 -25);
FORCEPROP 2 LAST PATH I212
J 0
(4275 50);
DISPLAY 1.021277 (4275 50);
DISPLAY INVISIBLE (4275 50);
FORCEPROP 1 LAST COMMENT_BODY TRUE
J 0
(4055 -120);
DISPLAY 0.872340 (4055 -120);
PAINT PEACH (4055 -120);
DISPLAY INVISIBLE (4055 -120);
FORCEPROP 1 LAST OFFPAGE TRUE
J 0
(4425 -150);
DISPLAY 0.872340 (4425 -150);
PAINT GREEN (4425 -150);
DISPLAY INVISIBLE (4425 -150);
FORCEPROP 2 LAST CDS_LIB standard
J 0
(4100 -25);
DISPLAY INVISIBLE (4100 -25);
FORCEADD Q_RES..1
(2750 -25);
FORCEPROP 1 LAST VALUE 4.7K
J 2
(3025 -25);
DISPLAY 0.510638 (3025 -25);
PAINT SKYBLUE (3025 -25);
FORCEPROP 1 LAST MATERIAL CHIP
J 0
(3125 -25);
DISPLAY 0.510638 (3125 -25);
PAINT SKYBLUE (3125 -25);
FORCEPROP 1 LAST PART_NUMBER CS24702FB06
J 0
(2700 75);
DISPLAY 0.510638 (2700 75);
PAINT WHITE (2700 75);
DISPLAY INVISIBLE (2700 75);
FORCEPROP 1 LAST PACK_TYPE 0402LF
J 0
(3000 -175);
DISPLAY 0.510638 (3000 -175);
PAINT SKYBLUE (3000 -175);
DISPLAY INVISIBLE (3000 -175);
FORCEPROP 1 LAST WATTAGE 1/16W
J 2
(2725 -175);
DISPLAY 0.510638 (2725 -175);
PAINT SKYBLUE (2725 -175);
DISPLAY INVISIBLE (2725 -175);
FORCEPROP 1 LAST PATH I213
J 0
(2700 125);
DISPLAY 0.978723 (2700 125);
PAINT WHITE (2700 125);
DISPLAY INVISIBLE (2700 125);
FORCEPROP 1 LAST TOLERANCE 1%
J 0
(2750 -125);
DISPLAY 0.510638 (2750 -125);
PAINT SKYBLUE (2750 -125);
DISPLAY INVISIBLE (2750 -125);
FORCEPROP 2 LAST CDS_LIB pure_quanta
J 0
(2750 -25);
DISPLAY INVISIBLE (2750 -25);
FORCEPROP 1 LAST LOCATION R774
J 2
(2600 -25);
DISPLAY 0.702128 (2600 -25);
PAINT YELLOW (2600 -25);
FORCEPROP 0 LAST $SEC 1
J 0
(2400 25);
DISPLAY INVISIBLE (2400 25);
FORCEPROP 0 LAST CDS_SEC 1
J 0
(2400 25);
DISPLAY INVISIBLE (2400 25);
FORCEPROP 1 LASTPIN (2650 -25) $PN 1
J 0
(2662 -13);
DISPLAY 0.808511 (2662 -13);
PAINT WHITE (2662 -13);
DISPLAY INVISIBLE (2662 -13);
FORCEPROP 1 LASTPIN (2850 -25) $PN 2
J 0
(2812 -13);
DISPLAY 0.808511 (2812 -13);
PAINT WHITE (2812 -13);
DISPLAY INVISIBLE (2812 -13);
FORCEADD OFFPAGE..5
R 2
(4925 2875);
FORCEPROP 2 LAST $XR0 15 
J 0
(5114 2875);
DISPLAY 0.638298 (5114 2875);
PAINT MONO (5114 2875);
FORCEPROP 2 LAST CDS_LIB standard
J 0
(4925 2875);
DISPLAY INVISIBLE (4925 2875);
FORCEPROP 1 LAST OFFPAGE TRUE
J 2
(4600 2750);
DISPLAY 0.872340 (4600 2750);
PAINT GREEN (4600 2750);
DISPLAY INVISIBLE (4600 2750);
FORCEPROP 1 LAST COMMENT_BODY TRUE
J 2
(4825 2800);
DISPLAY 0.872340 (4825 2800);
PAINT PEACH (4825 2800);
DISPLAY INVISIBLE (4825 2800);
FORCEPROP 2 LAST PATH I214
J 0
(5100 2950);
DISPLAY 1.021277 (5100 2950);
DISPLAY INVISIBLE (5100 2950);
FORCEADD Q_RES..1
(-1825 3725);
FORCEPROP 1 LAST VALUE 33.2
J 0
(-1750 3725);
DISPLAY 0.510638 (-1750 3725);
PAINT SKYBLUE (-1750 3725);
FORCEPROP 1 LAST MATERIAL CHIP
J 0
(-1975 3725);
DISPLAY 0.510638 (-1975 3725);
PAINT SKYBLUE (-1975 3725);
FORCEPROP 1 LAST TOLERANCE 1%
J 0
(-1700 3725);
DISPLAY 0.510638 (-1700 3725);
PAINT SKYBLUE (-1700 3725);
DISPLAY INVISIBLE (-1700 3725);
FORCEPROP 1 LAST PART_NUMBER CS03322FB03
J 0
(-1875 3825);
DISPLAY 0.510638 (-1875 3825);
PAINT WHITE (-1875 3825);
DISPLAY INVISIBLE (-1875 3825);
FORCEPROP 1 LAST PACK_TYPE 0402LF
J 0
(-1575 3575);
DISPLAY 0.510638 (-1575 3575);
PAINT SKYBLUE (-1575 3575);
DISPLAY INVISIBLE (-1575 3575);
FORCEPROP 1 LAST WATTAGE 1/16W
J 2
(-1850 3575);
DISPLAY 0.510638 (-1850 3575);
PAINT SKYBLUE (-1850 3575);
DISPLAY INVISIBLE (-1850 3575);
FORCEPROP 1 LAST PATH I215
J 0
(-1875 3875);
DISPLAY 0.978723 (-1875 3875);
PAINT WHITE (-1875 3875);
DISPLAY INVISIBLE (-1875 3875);
FORCEPROP 2 LAST CDS_LIB pure_quanta
J 0
(-1825 3725);
DISPLAY INVISIBLE (-1825 3725);
FORCEPROP 1 LAST LOCATION R799
J 0
(-2100 3725);
DISPLAY 0.702128 (-2100 3725);
PAINT YELLOW (-2100 3725);
FORCEPROP 0 LAST $SEC 1
J 0
(-1875 3825);
DISPLAY 0.680851 (-1875 3825);
PAINT MONO (-1875 3825);
DISPLAY INVISIBLE (-1875 3825);
FORCEPROP 0 LAST CDS_SEC 1
J 0
(-1875 3825);
DISPLAY 1.021277 (-1875 3825);
DISPLAY INVISIBLE (-1875 3825);
FORCEPROP 1 LASTPIN (-1925 3725) $PN 1
J 0
(-1913 3737);
DISPLAY 0.808511 (-1913 3737);
PAINT WHITE (-1913 3737);
DISPLAY INVISIBLE (-1913 3737);
FORCEPROP 1 LASTPIN (-1725 3725) $PN 2
J 0
(-1763 3737);
DISPLAY 0.808511 (-1763 3737);
PAINT WHITE (-1763 3737);
DISPLAY INVISIBLE (-1763 3737);
FORCEADD Q_RES..1
(-1775 4325);
FORCEPROP 1 LAST MATERIAL CHIP
J 0
(-1925 4325);
DISPLAY 0.510638 (-1925 4325);
PAINT SKYBLUE (-1925 4325);
FORCEPROP 1 LAST VALUE 33.2
J 0
(-1700 4325);
DISPLAY 0.510638 (-1700 4325);
PAINT SKYBLUE (-1700 4325);
FORCEPROP 1 LAST WATTAGE 1/16W
J 2
(-1800 4175);
DISPLAY 0.510638 (-1800 4175);
PAINT SKYBLUE (-1800 4175);
DISPLAY INVISIBLE (-1800 4175);
FORCEPROP 1 LAST PACK_TYPE 0402LF
J 0
(-1525 4175);
DISPLAY 0.510638 (-1525 4175);
PAINT SKYBLUE (-1525 4175);
DISPLAY INVISIBLE (-1525 4175);
FORCEPROP 1 LAST PART_NUMBER CS03322FB03
J 0
(-1825 4425);
DISPLAY 0.510638 (-1825 4425);
PAINT WHITE (-1825 4425);
DISPLAY INVISIBLE (-1825 4425);
FORCEPROP 1 LAST TOLERANCE 1%
J 0
(-1650 4325);
DISPLAY 0.510638 (-1650 4325);
PAINT SKYBLUE (-1650 4325);
DISPLAY INVISIBLE (-1650 4325);
FORCEPROP 1 LAST PATH I217
J 0
(-1825 4475);
DISPLAY 0.978723 (-1825 4475);
PAINT WHITE (-1825 4475);
DISPLAY INVISIBLE (-1825 4475);
FORCEPROP 2 LAST CDS_LIB pure_quanta
J 0
(-1775 4325);
DISPLAY INVISIBLE (-1775 4325);
FORCEPROP 1 LAST LOCATION R801
J 0
(-2050 4325);
DISPLAY 0.702128 (-2050 4325);
PAINT YELLOW (-2050 4325);
FORCEPROP 0 LAST $SEC 1
J 0
(-1825 4425);
DISPLAY 0.680851 (-1825 4425);
PAINT MONO (-1825 4425);
DISPLAY INVISIBLE (-1825 4425);
FORCEPROP 0 LAST CDS_SEC 1
J 0
(-1825 4425);
DISPLAY 1.021277 (-1825 4425);
DISPLAY INVISIBLE (-1825 4425);
FORCEPROP 1 LASTPIN (-1875 4325) $PN 1
J 0
(-1863 4337);
DISPLAY 0.808511 (-1863 4337);
PAINT WHITE (-1863 4337);
DISPLAY INVISIBLE (-1863 4337);
FORCEPROP 1 LASTPIN (-1675 4325) $PN 2
J 0
(-1713 4337);
DISPLAY 0.808511 (-1713 4337);
PAINT WHITE (-1713 4337);
DISPLAY INVISIBLE (-1713 4337);
FORCEADD Q_RES..1
(-1775 4275);
FORCEPROP 1 LAST MATERIAL CHIP
J 0
(-1925 4275);
DISPLAY 0.510638 (-1925 4275);
PAINT SKYBLUE (-1925 4275);
FORCEPROP 1 LAST VALUE 33.2
J 0
(-1700 4275);
DISPLAY 0.510638 (-1700 4275);
PAINT SKYBLUE (-1700 4275);
FORCEPROP 1 LAST WATTAGE 1/16W
J 2
(-1800 4125);
DISPLAY 0.510638 (-1800 4125);
PAINT SKYBLUE (-1800 4125);
DISPLAY INVISIBLE (-1800 4125);
FORCEPROP 1 LAST PACK_TYPE 0402LF
J 0
(-1525 4125);
DISPLAY 0.510638 (-1525 4125);
PAINT SKYBLUE (-1525 4125);
DISPLAY INVISIBLE (-1525 4125);
FORCEPROP 1 LAST PART_NUMBER CS03322FB03
J 0
(-1825 4375);
DISPLAY 0.510638 (-1825 4375);
PAINT WHITE (-1825 4375);
DISPLAY INVISIBLE (-1825 4375);
FORCEPROP 1 LAST TOLERANCE 1%
J 0
(-1650 4275);
DISPLAY 0.510638 (-1650 4275);
PAINT SKYBLUE (-1650 4275);
DISPLAY INVISIBLE (-1650 4275);
FORCEPROP 1 LAST PATH I218
J 0
(-1825 4425);
DISPLAY 0.978723 (-1825 4425);
PAINT WHITE (-1825 4425);
DISPLAY INVISIBLE (-1825 4425);
FORCEPROP 2 LAST CDS_LIB pure_quanta
J 0
(-1775 4275);
DISPLAY INVISIBLE (-1775 4275);
FORCEPROP 1 LAST LOCATION R802
J 0
(-2050 4275);
DISPLAY 0.702128 (-2050 4275);
PAINT YELLOW (-2050 4275);
FORCEPROP 0 LAST $SEC 1
J 0
(-1825 4375);
DISPLAY 0.680851 (-1825 4375);
PAINT MONO (-1825 4375);
DISPLAY INVISIBLE (-1825 4375);
FORCEPROP 0 LAST CDS_SEC 1
J 0
(-1825 4375);
DISPLAY 1.021277 (-1825 4375);
DISPLAY INVISIBLE (-1825 4375);
FORCEPROP 1 LASTPIN (-1875 4275) $PN 1
J 0
(-1863 4287);
DISPLAY 0.808511 (-1863 4287);
PAINT WHITE (-1863 4287);
DISPLAY INVISIBLE (-1863 4287);
FORCEPROP 1 LASTPIN (-1675 4275) $PN 2
J 0
(-1713 4287);
DISPLAY 0.808511 (-1713 4287);
PAINT WHITE (-1713 4287);
DISPLAY INVISIBLE (-1713 4287);
FORCEADD OFFPAGE..2
(4100 -75);
FORCEPROP 2 LAST $XR2 35 
J 0
(4469 -75);
DISPLAY 0.638298 (4469 -75);
PAINT MONO (4469 -75);
FORCEPROP 2 LAST $XR1 27 
J 0
(4379 -75);
DISPLAY 0.638298 (4379 -75);
PAINT MONO (4379 -75);
FORCEPROP 2 LAST $XR0 13 
J 0
(4289 -75);
DISPLAY 0.638298 (4289 -75);
PAINT MONO (4289 -75);
FORCEPROP 2 LAST PATH I219
J 0
(4400 -25);
DISPLAY 1.021277 (4400 -25);
DISPLAY INVISIBLE (4400 -25);
FORCEPROP 1 LAST COMMENT_BODY TRUE
J 0
(4055 -170);
DISPLAY 0.872340 (4055 -170);
PAINT PEACH (4055 -170);
DISPLAY INVISIBLE (4055 -170);
FORCEPROP 1 LAST OFFPAGE TRUE
J 0
(4425 -200);
DISPLAY 0.872340 (4425 -200);
PAINT GREEN (4425 -200);
DISPLAY INVISIBLE (4425 -200);
FORCEPROP 2 LAST CDS_LIB standard
J 0
(4100 -75);
DISPLAY INVISIBLE (4100 -75);
FORCEADD OFFPAGE..5
(-2975 3025);
FORCEPROP 2 LAST $XR0 34 
J 0
(-3229 3025);
DISPLAY 0.638298 (-3229 3025);
PAINT MONO (-3229 3025);
FORCEPROP 2 LAST CDS_LIB standard
J 2
(-2975 3025);
DISPLAY INVISIBLE (-2975 3025);
FORCEPROP 1 LAST OFFPAGE TRUE
J 0
(-2650 2900);
DISPLAY 0.872340 (-2650 2900);
PAINT GREEN (-2650 2900);
DISPLAY INVISIBLE (-2650 2900);
FORCEPROP 1 LAST COMMENT_BODY TRUE
J 0
(-2875 2950);
DISPLAY 0.872340 (-2875 2950);
PAINT PEACH (-2875 2950);
DISPLAY INVISIBLE (-2875 2950);
FORCEPROP 2 LAST PATH I22
J 0
(-3175 3075);
DISPLAY 1.021277 (-3175 3075);
DISPLAY INVISIBLE (-3175 3075);
FORCEADD Q_RES..1
(2750 -75);
FORCEPROP 1 LAST VALUE 4.7K
J 2
(3025 -75);
DISPLAY 0.510638 (3025 -75);
PAINT SKYBLUE (3025 -75);
FORCEPROP 1 LAST MATERIAL EMPTY
J 0
(3125 -75);
DISPLAY 0.510638 (3125 -75);
PAINT RED (3125 -75);
FORCEPROP 1 LAST PART_NUMBER CS24702FB06
J 0
(2700 25);
DISPLAY 0.510638 (2700 25);
PAINT WHITE (2700 25);
DISPLAY INVISIBLE (2700 25);
FORCEPROP 1 LAST PACK_TYPE 0402LF
J 0
(3000 -225);
DISPLAY 0.510638 (3000 -225);
PAINT SKYBLUE (3000 -225);
DISPLAY INVISIBLE (3000 -225);
FORCEPROP 1 LAST WATTAGE 1/16W
J 2
(2725 -225);
DISPLAY 0.510638 (2725 -225);
PAINT SKYBLUE (2725 -225);
DISPLAY INVISIBLE (2725 -225);
FORCEPROP 1 LAST PATH I220
J 0
(2700 75);
DISPLAY 0.978723 (2700 75);
PAINT WHITE (2700 75);
DISPLAY INVISIBLE (2700 75);
FORCEPROP 1 LAST TOLERANCE 1%
J 0
(2750 -175);
DISPLAY 0.510638 (2750 -175);
PAINT SKYBLUE (2750 -175);
DISPLAY INVISIBLE (2750 -175);
FORCEPROP 2 LAST CDS_LIB pure_quanta
J 0
(2750 -75);
DISPLAY INVISIBLE (2750 -75);
FORCEPROP 1 LAST LOCATION R821
J 2
(2600 -75);
DISPLAY 0.702128 (2600 -75);
PAINT YELLOW (2600 -75);
FORCEPROP 0 LAST $SEC 1
J 0
(2400 -25);
DISPLAY INVISIBLE (2400 -25);
FORCEPROP 0 LAST CDS_SEC 1
J 0
(2400 -25);
DISPLAY INVISIBLE (2400 -25);
FORCEPROP 1 LASTPIN (2650 -75) $PN 1
J 0
(2662 -63);
DISPLAY 0.808511 (2662 -63);
PAINT WHITE (2662 -63);
DISPLAY INVISIBLE (2662 -63);
FORCEPROP 1 LASTPIN (2850 -75) $PN 2
J 0
(2812 -63);
DISPLAY 0.808511 (2812 -63);
PAINT WHITE (2812 -63);
DISPLAY INVISIBLE (2812 -63);
FORCEADD Q_RES..1
(-2300 2425);
FORCEPROP 1 LAST VALUE 33.2
J 0
(-2200 2425);
DISPLAY 0.510638 (-2200 2425);
PAINT SKYBLUE (-2200 2425);
FORCEPROP 1 LAST MATERIAL CHIP
J 0
(-2100 2425);
DISPLAY 0.510638 (-2100 2425);
PAINT SKYBLUE (-2100 2425);
FORCEPROP 1 LAST TOLERANCE 1%
J 0
(-2175 2425);
DISPLAY 0.510638 (-2175 2425);
PAINT SKYBLUE (-2175 2425);
DISPLAY INVISIBLE (-2175 2425);
FORCEPROP 1 LAST PART_NUMBER CS03322FB03
J 0
(-2350 2525);
DISPLAY 0.510638 (-2350 2525);
PAINT WHITE (-2350 2525);
DISPLAY INVISIBLE (-2350 2525);
FORCEPROP 1 LAST PACK_TYPE 0402LF
J 0
(-2050 2275);
DISPLAY 0.510638 (-2050 2275);
PAINT SKYBLUE (-2050 2275);
DISPLAY INVISIBLE (-2050 2275);
FORCEPROP 1 LAST WATTAGE 1/16W
J 2
(-2325 2275);
DISPLAY 0.510638 (-2325 2275);
PAINT SKYBLUE (-2325 2275);
DISPLAY INVISIBLE (-2325 2275);
FORCEPROP 1 LAST PATH I223
J 0
(-2350 2575);
DISPLAY 0.978723 (-2350 2575);
PAINT WHITE (-2350 2575);
DISPLAY INVISIBLE (-2350 2575);
FORCEPROP 2 LAST CDS_LIB pure_quanta
J 0
(-2300 2425);
DISPLAY INVISIBLE (-2300 2425);
FORCEPROP 1 LAST LOCATION R824
J 0
(-2525 2425);
DISPLAY 0.702128 (-2525 2425);
PAINT YELLOW (-2525 2425);
FORCEPROP 1 LASTPIN (-2400 2425) $PN 1
J 0
(-2388 2437);
DISPLAY 0.808511 (-2388 2437);
PAINT WHITE (-2388 2437);
FORCEPROP 1 LASTPIN (-2200 2425) $PN 2
J 0
(-2238 2437);
DISPLAY 0.808511 (-2238 2437);
PAINT WHITE (-2238 2437);
FORCEPROP 2 LAST $SEC 1
J 0
(-2350 2625);
DISPLAY 0.680851 (-2350 2625);
PAINT MONO (-2350 2625);
DISPLAY INVISIBLE (-2350 2625);
FORCEPROP 0 LAST CDS_SEC 1
J 0
(-2350 2625);
DISPLAY 0.680851 (-2350 2625);
PAINT MONO (-2350 2625);
DISPLAY INVISIBLE (-2350 2625);
FORCEADD OFFPAGE..5
(-3425 2425);
FORCEPROP 2 LAST $XR1 10 
J 0
(-3769 2425);
DISPLAY 0.638298 (-3769 2425);
PAINT MONO (-3769 2425);
FORCEPROP 2 LAST $XR0 11 
J 0
(-3679 2425);
DISPLAY 0.638298 (-3679 2425);
PAINT MONO (-3679 2425);
FORCEPROP 2 LAST PATH I224
J 0
(-3375 2500);
DISPLAY 1.021277 (-3375 2500);
DISPLAY INVISIBLE (-3375 2500);
FORCEPROP 1 LAST COMMENT_BODY TRUE
J 0
(-3325 2350);
DISPLAY 0.872340 (-3325 2350);
PAINT PEACH (-3325 2350);
DISPLAY INVISIBLE (-3325 2350);
FORCEPROP 1 LAST OFFPAGE TRUE
J 0
(-3100 2300);
DISPLAY 0.872340 (-3100 2300);
PAINT GREEN (-3100 2300);
DISPLAY INVISIBLE (-3100 2300);
FORCEPROP 2 LAST CDS_LIB standard
J 0
(-3425 2425);
DISPLAY INVISIBLE (-3425 2425);
FORCEADD Q_RES..1
(-2300 2375);
FORCEPROP 1 LAST MATERIAL CHIP
J 0
(-2100 2375);
DISPLAY 0.510638 (-2100 2375);
PAINT SKYBLUE (-2100 2375);
FORCEPROP 1 LAST VALUE 33.2
J 0
(-2200 2375);
DISPLAY 0.510638 (-2200 2375);
PAINT SKYBLUE (-2200 2375);
FORCEPROP 1 LAST TOLERANCE 1%
J 0
(-2175 2375);
DISPLAY 0.510638 (-2175 2375);
PAINT SKYBLUE (-2175 2375);
DISPLAY INVISIBLE (-2175 2375);
FORCEPROP 1 LAST PART_NUMBER CS03322FB03
J 0
(-2350 2475);
DISPLAY 0.510638 (-2350 2475);
PAINT WHITE (-2350 2475);
DISPLAY INVISIBLE (-2350 2475);
FORCEPROP 1 LAST PACK_TYPE 0402LF
J 0
(-2050 2225);
DISPLAY 0.510638 (-2050 2225);
PAINT SKYBLUE (-2050 2225);
DISPLAY INVISIBLE (-2050 2225);
FORCEPROP 1 LAST WATTAGE 1/16W
J 2
(-2325 2225);
DISPLAY 0.510638 (-2325 2225);
PAINT SKYBLUE (-2325 2225);
DISPLAY INVISIBLE (-2325 2225);
FORCEPROP 1 LAST PATH I225
J 0
(-2350 2525);
DISPLAY 0.978723 (-2350 2525);
PAINT WHITE (-2350 2525);
DISPLAY INVISIBLE (-2350 2525);
FORCEPROP 2 LAST CDS_LIB pure_quanta
J 0
(-2300 2375);
DISPLAY INVISIBLE (-2300 2375);
FORCEPROP 1 LAST LOCATION R836
J 0
(-2525 2375);
DISPLAY 0.702128 (-2525 2375);
PAINT YELLOW (-2525 2375);
FORCEPROP 1 LASTPIN (-2400 2375) $PN 1
J 0
(-2388 2387);
DISPLAY 0.808511 (-2388 2387);
PAINT WHITE (-2388 2387);
FORCEPROP 1 LASTPIN (-2200 2375) $PN 2
J 0
(-2238 2387);
DISPLAY 0.808511 (-2238 2387);
PAINT WHITE (-2238 2387);
FORCEPROP 0 LAST $SEC 1
J 0
(-2350 2475);
DISPLAY 0.680851 (-2350 2475);
PAINT MONO (-2350 2475);
DISPLAY INVISIBLE (-2350 2475);
FORCEPROP 0 LAST CDS_SEC 1
J 0
(-2350 2475);
DISPLAY 0.680851 (-2350 2475);
DISPLAY INVISIBLE (-2350 2475);
FORCEADD OFFPAGE..1
(-3425 2375);
FORCEPROP 2 LAST $XR4 34 
J 0
(-4036 2375);
DISPLAY 0.638298 (-4036 2375);
PAINT MONO (-4036 2375);
FORCEPROP 2 LAST $XR3 28 
J 0
(-3946 2375);
DISPLAY 0.638298 (-3946 2375);
PAINT MONO (-3946 2375);
FORCEPROP 2 LAST $XR2 22 
J 0
(-3856 2375);
DISPLAY 0.638298 (-3856 2375);
PAINT MONO (-3856 2375);
FORCEPROP 2 LAST $XR1 11 
J 0
(-3766 2375);
DISPLAY 0.638298 (-3766 2375);
PAINT MONO (-3766 2375);
FORCEPROP 2 LAST $XR0 10 
J 0
(-3676 2375);
DISPLAY 0.638298 (-3676 2375);
PAINT MONO (-3676 2375);
FORCEPROP 2 LAST PATH I226
J 0
(-3625 2425);
DISPLAY 1.021277 (-3625 2425);
DISPLAY INVISIBLE (-3625 2425);
FORCEPROP 1 LAST COMMENT_BODY TRUE
J 0
(-3300 2275);
DISPLAY 0.872340 (-3300 2275);
PAINT PEACH (-3300 2275);
DISPLAY INVISIBLE (-3300 2275);
FORCEPROP 1 LAST OFFPAGE TRUE
J 0
(-3100 2250);
DISPLAY 0.872340 (-3100 2250);
PAINT GREEN (-3100 2250);
DISPLAY INVISIBLE (-3100 2250);
FORCEPROP 2 LAST CDS_LIB standard
J 0
(-3425 2375);
DISPLAY INVISIBLE (-3425 2375);
FORCEADD Q_RES..1
(-2300 2325);
FORCEPROP 1 LAST VALUE 33.2
J 0
(-2200 2325);
DISPLAY 0.510638 (-2200 2325);
PAINT SKYBLUE (-2200 2325);
FORCEPROP 1 LAST MATERIAL CHIP
J 0
(-2100 2325);
DISPLAY 0.510638 (-2100 2325);
PAINT SKYBLUE (-2100 2325);
FORCEPROP 1 LAST TOLERANCE 1%
J 0
(-2175 2325);
DISPLAY 0.510638 (-2175 2325);
PAINT SKYBLUE (-2175 2325);
DISPLAY INVISIBLE (-2175 2325);
FORCEPROP 1 LAST PART_NUMBER CS03322FB03
J 0
(-2350 2425);
DISPLAY 0.510638 (-2350 2425);
PAINT WHITE (-2350 2425);
DISPLAY INVISIBLE (-2350 2425);
FORCEPROP 1 LAST PACK_TYPE 0402LF
J 0
(-2050 2175);
DISPLAY 0.510638 (-2050 2175);
PAINT SKYBLUE (-2050 2175);
DISPLAY INVISIBLE (-2050 2175);
FORCEPROP 1 LAST WATTAGE 1/16W
J 2
(-2325 2175);
DISPLAY 0.510638 (-2325 2175);
PAINT SKYBLUE (-2325 2175);
DISPLAY INVISIBLE (-2325 2175);
FORCEPROP 1 LAST PATH I227
J 0
(-2350 2475);
DISPLAY 0.978723 (-2350 2475);
PAINT WHITE (-2350 2475);
DISPLAY INVISIBLE (-2350 2475);
FORCEPROP 2 LAST CDS_LIB pure_quanta
J 0
(-2300 2325);
DISPLAY INVISIBLE (-2300 2325);
FORCEPROP 1 LAST LOCATION R439
J 0
(-2525 2325);
DISPLAY 0.702128 (-2525 2325);
PAINT YELLOW (-2525 2325);
FORCEPROP 1 LASTPIN (-2400 2325) $PN 1
J 0
(-2388 2337);
DISPLAY 0.808511 (-2388 2337);
PAINT WHITE (-2388 2337);
FORCEPROP 1 LASTPIN (-2200 2325) $PN 2
J 0
(-2238 2337);
DISPLAY 0.808511 (-2238 2337);
PAINT WHITE (-2238 2337);
FORCEPROP 0 LAST $SEC 1
J 0
(-2350 2425);
DISPLAY 0.680851 (-2350 2425);
PAINT MONO (-2350 2425);
DISPLAY INVISIBLE (-2350 2425);
FORCEPROP 0 LAST CDS_SEC 1
J 0
(-2350 2425);
DISPLAY 0.680851 (-2350 2425);
DISPLAY INVISIBLE (-2350 2425);
FORCEADD OFFPAGE..1
(-2975 3325);
FORCEPROP 2 LAST $XR0 27 
J 0
(-3196 3325);
DISPLAY 0.638298 (-3196 3325);
PAINT MONO (-3196 3325);
FORCEPROP 2 LAST $XR1 35 
J 0
(-3286 3325);
DISPLAY 0.638298 (-3286 3325);
PAINT MONO (-3286 3325);
FORCEPROP 2 LAST CDS_LIB standard
J 0
(-2975 3325);
DISPLAY INVISIBLE (-2975 3325);
FORCEPROP 1 LAST OFFPAGE TRUE
J 0
(-2650 3200);
DISPLAY 0.872340 (-2650 3200);
DISPLAY INVISIBLE (-2650 3200);
FORCEPROP 1 LAST COMMENT_BODY TRUE
J 0
(-2850 3225);
DISPLAY 0.872340 (-2850 3225);
PAINT GREEN (-2850 3225);
DISPLAY INVISIBLE (-2850 3225);
FORCEPROP 2 LAST PATH I229
J 0
(-2925 3400);
DISPLAY 1.021277 (-2925 3400);
DISPLAY INVISIBLE (-2925 3400);
FORCEADD OFFPAGE..4
(4925 2725);
FORCEPROP 2 LAST $XR0 46 
J 0
(5111 2725);
DISPLAY 0.638298 (5111 2725);
PAINT MONO (5111 2725);
FORCEPROP 2 LAST CDS_LIB standard
J 0
(4925 2725);
DISPLAY INVISIBLE (4925 2725);
FORCEPROP 1 LAST OFFPAGE TRUE
J 0
(5250 2600);
DISPLAY 0.872340 (5250 2600);
DISPLAY INVISIBLE (5250 2600);
FORCEPROP 1 LAST COMMENT_BODY TRUE
J 0
(4900 2625);
DISPLAY 0.872340 (4900 2625);
PAINT GREEN (4900 2625);
DISPLAY INVISIBLE (4900 2625);
FORCEPROP 2 LAST PATH I236
J 0
(5250 2775);
DISPLAY 1.021277 (5250 2775);
DISPLAY INVISIBLE (5250 2775);
FORCEADD Q_RES..1
(3350 4750);
FORCEPROP 1 LAST MATERIAL EMPTY
J 0
(3600 4750);
DISPLAY 0.510638 (3600 4750);
PAINT RED (3600 4750);
FORCEPROP 1 LAST VALUE 33.2
J 2
(3575 4750);
DISPLAY 0.510638 (3575 4750);
PAINT SKYBLUE (3575 4750);
FORCEPROP 1 LAST TOLERANCE 1%
J 0
(3275 4850);
DISPLAY 0.510638 (3275 4850);
PAINT SKYBLUE (3275 4850);
DISPLAY INVISIBLE (3275 4850);
FORCEPROP 1 LAST PART_NUMBER CS03322FB03
J 0
(3250 4825);
DISPLAY 0.510638 (3250 4825);
PAINT WHITE (3250 4825);
DISPLAY INVISIBLE (3250 4825);
FORCEPROP 1 LAST PACK_TYPE 0402LF
J 0
(3325 4800);
DISPLAY 0.510638 (3325 4800);
PAINT SKYBLUE (3325 4800);
DISPLAY INVISIBLE (3325 4800);
FORCEPROP 1 LAST WATTAGE 1/16W
J 2
(3700 4850);
DISPLAY 0.510638 (3700 4850);
PAINT SKYBLUE (3700 4850);
DISPLAY INVISIBLE (3700 4850);
FORCEPROP 1 LAST PATH I239
J 0
(3300 4900);
DISPLAY 0.978723 (3300 4900);
PAINT WHITE (3300 4900);
DISPLAY INVISIBLE (3300 4900);
FORCEPROP 2 LAST CDS_LIB pure_quanta
J 0
(3350 4750);
DISPLAY INVISIBLE (3350 4750);
FORCEPROP 1 LAST LOCATION R678
J 0
(3125 4750);
DISPLAY 0.702128 (3125 4750);
PAINT YELLOW (3125 4750);
FORCEPROP 0 LAST $SEC 1
J 0
(3125 4800);
DISPLAY 0.680851 (3125 4800);
PAINT MONO (3125 4800);
DISPLAY INVISIBLE (3125 4800);
FORCEPROP 0 LAST CDS_SEC 1
J 0
(3125 4800);
DISPLAY 0.680851 (3125 4800);
DISPLAY INVISIBLE (3125 4800);
FORCEPROP 1 LASTPIN (3250 4750) $PN 1
J 0
(3262 4762);
DISPLAY 0.808511 (3262 4762);
PAINT WHITE (3262 4762);
DISPLAY INVISIBLE (3262 4762);
FORCEPROP 1 LASTPIN (3450 4750) $PN 2
J 0
(3412 4762);
DISPLAY 0.808511 (3412 4762);
PAINT WHITE (3412 4762);
DISPLAY INVISIBLE (3412 4762);
FORCEADD OFFPAGE..1
(-2975 3625);
FORCEPROP 2 LAST $XR0 10 
J 0
(-3196 3625);
DISPLAY 0.638298 (-3196 3625);
PAINT MONO (-3196 3625);
FORCEPROP 2 LAST CDS_LIB standard
J 2
(-2975 3625);
DISPLAY INVISIBLE (-2975 3625);
FORCEPROP 1 LAST OFFPAGE TRUE
J 0
(-2650 3500);
DISPLAY 0.872340 (-2650 3500);
DISPLAY INVISIBLE (-2650 3500);
FORCEPROP 1 LAST COMMENT_BODY TRUE
J 0
(-2850 3525);
DISPLAY 0.872340 (-2850 3525);
PAINT GREEN (-2850 3525);
DISPLAY INVISIBLE (-2850 3525);
FORCEPROP 2 LAST PATH I24
J 0
(-3175 3675);
DISPLAY 1.021277 (-3175 3675);
DISPLAY INVISIBLE (-3175 3675);
FORCEADD OFFPAGE..4
(4475 4750);
FORCEPROP 2 LAST $XR0 10 
J 0
(4661 4750);
DISPLAY 0.638298 (4661 4750);
PAINT MONO (4661 4750);
FORCEPROP 2 LAST PATH I240
J 0
(4675 4800);
DISPLAY 1.021277 (4675 4800);
DISPLAY INVISIBLE (4675 4800);
FORCEPROP 1 LAST COMMENT_BODY TRUE
J 0
(4450 4650);
DISPLAY 0.872340 (4450 4650);
PAINT PEACH (4450 4650);
DISPLAY INVISIBLE (4450 4650);
FORCEPROP 1 LAST OFFPAGE TRUE
J 0
(4800 4625);
DISPLAY 0.872340 (4800 4625);
PAINT GREEN (4800 4625);
DISPLAY INVISIBLE (4800 4625);
FORCEPROP 2 LAST CDS_LIB standard
J 0
(4475 4750);
DISPLAY INVISIBLE (4475 4750);
FORCEADD OFFPAGE..4
(4475 4700);
FORCEPROP 2 LAST $XR0 10 
J 0
(4661 4700);
DISPLAY 0.638298 (4661 4700);
PAINT MONO (4661 4700);
FORCEPROP 2 LAST PATH I241
J 0
(4675 4750);
DISPLAY 1.021277 (4675 4750);
DISPLAY INVISIBLE (4675 4750);
FORCEPROP 1 LAST COMMENT_BODY TRUE
J 0
(4450 4600);
DISPLAY 0.872340 (4450 4600);
PAINT PEACH (4450 4600);
DISPLAY INVISIBLE (4450 4600);
FORCEPROP 1 LAST OFFPAGE TRUE
J 0
(4800 4575);
DISPLAY 0.872340 (4800 4575);
PAINT GREEN (4800 4575);
DISPLAY INVISIBLE (4800 4575);
FORCEPROP 2 LAST CDS_LIB standard
J 0
(4475 4700);
DISPLAY INVISIBLE (4475 4700);
FORCEADD OFFPAGE..4
(4475 4600);
FORCEPROP 2 LAST $XR0 10 
J 0
(4661 4600);
DISPLAY 0.638298 (4661 4600);
PAINT MONO (4661 4600);
FORCEPROP 2 LAST PATH I242
J 0
(4700 4650);
DISPLAY 1.021277 (4700 4650);
DISPLAY INVISIBLE (4700 4650);
FORCEPROP 1 LAST COMMENT_BODY TRUE
J 0
(4450 4500);
DISPLAY 0.872340 (4450 4500);
PAINT PEACH (4450 4500);
DISPLAY INVISIBLE (4450 4500);
FORCEPROP 1 LAST OFFPAGE TRUE
J 0
(4800 4475);
DISPLAY 0.872340 (4800 4475);
PAINT GREEN (4800 4475);
DISPLAY INVISIBLE (4800 4475);
FORCEPROP 2 LAST CDS_LIB standard
J 0
(4475 4600);
DISPLAY INVISIBLE (4475 4600);
FORCEADD OFFPAGE..2
(4475 4650);
FORCEPROP 2 LAST $XR0 10 
J 0
(4664 4650);
DISPLAY 0.638298 (4664 4650);
PAINT MONO (4664 4650);
FORCEPROP 2 LAST PATH I243
J 0
(4675 4700);
DISPLAY 1.021277 (4675 4700);
DISPLAY INVISIBLE (4675 4700);
FORCEPROP 1 LAST COMMENT_BODY TRUE
J 0
(4430 4555);
DISPLAY 0.872340 (4430 4555);
PAINT PEACH (4430 4555);
DISPLAY INVISIBLE (4430 4555);
FORCEPROP 1 LAST OFFPAGE TRUE
J 0
(4800 4525);
DISPLAY 0.872340 (4800 4525);
PAINT GREEN (4800 4525);
DISPLAY INVISIBLE (4800 4525);
FORCEPROP 2 LAST CDS_LIB standard
J 0
(4475 4650);
DISPLAY INVISIBLE (4475 4650);
FORCEADD OFFPAGE..4
(4475 4550);
FORCEPROP 2 LAST $XR0 10 
J 0
(4661 4550);
DISPLAY 0.638298 (4661 4550);
PAINT MONO (4661 4550);
FORCEPROP 2 LAST CDS_LIB standard
J 0
(4475 4550);
DISPLAY INVISIBLE (4475 4550);
FORCEPROP 2 LAST PATH I244
J 0
(4700 4600);
DISPLAY 1.021277 (4700 4600);
DISPLAY INVISIBLE (4700 4600);
FORCEPROP 1 LAST COMMENT_BODY TRUE
J 0
(4450 4450);
DISPLAY 0.872340 (4450 4450);
PAINT PEACH (4450 4450);
DISPLAY INVISIBLE (4450 4450);
FORCEPROP 1 LAST OFFPAGE TRUE
J 0
(4800 4425);
DISPLAY 0.872340 (4800 4425);
PAINT GREEN (4800 4425);
DISPLAY INVISIBLE (4800 4425);
FORCEADD Q_RES..1
(3350 4600);
FORCEPROP 1 LAST VALUE 33.2
J 2
(3575 4600);
DISPLAY 0.510638 (3575 4600);
PAINT SKYBLUE (3575 4600);
FORCEPROP 1 LAST MATERIAL EMPTY
J 0
(3600 4600);
DISPLAY 0.510638 (3600 4600);
PAINT RED (3600 4600);
FORCEPROP 1 LAST TOLERANCE 1%
J 0
(3275 4700);
DISPLAY 0.510638 (3275 4700);
PAINT SKYBLUE (3275 4700);
DISPLAY INVISIBLE (3275 4700);
FORCEPROP 1 LAST PART_NUMBER CS03322FB03
J 0
(3250 4675);
DISPLAY 0.510638 (3250 4675);
PAINT WHITE (3250 4675);
DISPLAY INVISIBLE (3250 4675);
FORCEPROP 1 LAST PACK_TYPE 0402LF
J 0
(3325 4650);
DISPLAY 0.510638 (3325 4650);
PAINT SKYBLUE (3325 4650);
DISPLAY INVISIBLE (3325 4650);
FORCEPROP 1 LAST WATTAGE 1/16W
J 2
(3700 4700);
DISPLAY 0.510638 (3700 4700);
PAINT SKYBLUE (3700 4700);
DISPLAY INVISIBLE (3700 4700);
FORCEPROP 1 LAST PATH I245
J 0
(3300 4750);
DISPLAY 0.978723 (3300 4750);
PAINT WHITE (3300 4750);
DISPLAY INVISIBLE (3300 4750);
FORCEPROP 2 LAST CDS_LIB pure_quanta
J 0
(3350 4600);
DISPLAY INVISIBLE (3350 4600);
FORCEPROP 1 LAST LOCATION R681
J 0
(3125 4600);
DISPLAY 0.702128 (3125 4600);
PAINT YELLOW (3125 4600);
FORCEPROP 0 LAST $SEC 1
J 0
(3125 4650);
DISPLAY 0.680851 (3125 4650);
PAINT MONO (3125 4650);
DISPLAY INVISIBLE (3125 4650);
FORCEPROP 0 LAST CDS_SEC 1
J 0
(3125 4650);
DISPLAY 1.021277 (3125 4650);
DISPLAY INVISIBLE (3125 4650);
FORCEPROP 1 LASTPIN (3250 4600) $PN 1
J 0
(3262 4612);
DISPLAY 0.808511 (3262 4612);
PAINT WHITE (3262 4612);
DISPLAY INVISIBLE (3262 4612);
FORCEPROP 1 LASTPIN (3450 4600) $PN 2
J 0
(3412 4612);
DISPLAY 0.808511 (3412 4612);
PAINT WHITE (3412 4612);
DISPLAY INVISIBLE (3412 4612);
FORCEADD Q_RES..1
(3350 4550);
FORCEPROP 1 LAST VALUE 33.2
J 2
(3575 4550);
DISPLAY 0.510638 (3575 4550);
PAINT SKYBLUE (3575 4550);
FORCEPROP 1 LAST MATERIAL EMPTY
J 0
(3600 4550);
DISPLAY 0.510638 (3600 4550);
PAINT RED (3600 4550);
FORCEPROP 1 LAST TOLERANCE 1%
J 0
(3275 4650);
DISPLAY 0.510638 (3275 4650);
PAINT SKYBLUE (3275 4650);
DISPLAY INVISIBLE (3275 4650);
FORCEPROP 1 LAST PART_NUMBER CS03322FB03
J 0
(3250 4625);
DISPLAY 0.510638 (3250 4625);
PAINT WHITE (3250 4625);
DISPLAY INVISIBLE (3250 4625);
FORCEPROP 1 LAST PACK_TYPE 0402LF
J 0
(3325 4600);
DISPLAY 0.510638 (3325 4600);
PAINT SKYBLUE (3325 4600);
DISPLAY INVISIBLE (3325 4600);
FORCEPROP 1 LAST WATTAGE 1/16W
J 2
(3700 4650);
DISPLAY 0.510638 (3700 4650);
PAINT SKYBLUE (3700 4650);
DISPLAY INVISIBLE (3700 4650);
FORCEPROP 1 LAST PATH I246
J 0
(3300 4700);
DISPLAY 0.978723 (3300 4700);
PAINT WHITE (3300 4700);
DISPLAY INVISIBLE (3300 4700);
FORCEPROP 2 LAST CDS_LIB pure_quanta
J 0
(3350 4550);
DISPLAY INVISIBLE (3350 4550);
FORCEPROP 1 LAST LOCATION R682
J 0
(3125 4550);
DISPLAY 0.702128 (3125 4550);
PAINT YELLOW (3125 4550);
FORCEPROP 0 LAST $SEC 1
J 0
(3125 4600);
DISPLAY 0.680851 (3125 4600);
PAINT MONO (3125 4600);
DISPLAY INVISIBLE (3125 4600);
FORCEPROP 0 LAST CDS_SEC 1
J 0
(3125 4600);
DISPLAY 1.021277 (3125 4600);
DISPLAY INVISIBLE (3125 4600);
FORCEPROP 1 LASTPIN (3250 4550) $PN 1
J 0
(3262 4562);
DISPLAY 0.808511 (3262 4562);
PAINT WHITE (3262 4562);
DISPLAY INVISIBLE (3262 4562);
FORCEPROP 1 LASTPIN (3450 4550) $PN 2
J 0
(3412 4562);
DISPLAY 0.808511 (3412 4562);
PAINT WHITE (3412 4562);
DISPLAY INVISIBLE (3412 4562);
FORCEADD Q_RES..1
(3350 4700);
FORCEPROP 1 LAST VALUE 33.2
J 2
(3575 4700);
DISPLAY 0.510638 (3575 4700);
PAINT SKYBLUE (3575 4700);
FORCEPROP 1 LAST MATERIAL EMPTY
J 0
(3600 4700);
DISPLAY 0.510638 (3600 4700);
PAINT RED (3600 4700);
FORCEPROP 1 LAST TOLERANCE 1%
J 0
(3275 4800);
DISPLAY 0.510638 (3275 4800);
PAINT SKYBLUE (3275 4800);
DISPLAY INVISIBLE (3275 4800);
FORCEPROP 1 LAST PART_NUMBER CS03322FB03
J 0
(3250 4775);
DISPLAY 0.510638 (3250 4775);
PAINT WHITE (3250 4775);
DISPLAY INVISIBLE (3250 4775);
FORCEPROP 1 LAST PACK_TYPE 0402LF
J 0
(3325 4750);
DISPLAY 0.510638 (3325 4750);
PAINT SKYBLUE (3325 4750);
DISPLAY INVISIBLE (3325 4750);
FORCEPROP 1 LAST WATTAGE 1/16W
J 2
(3700 4800);
DISPLAY 0.510638 (3700 4800);
PAINT SKYBLUE (3700 4800);
DISPLAY INVISIBLE (3700 4800);
FORCEPROP 1 LAST PATH I247
J 0
(3300 4850);
DISPLAY 0.978723 (3300 4850);
PAINT WHITE (3300 4850);
DISPLAY INVISIBLE (3300 4850);
FORCEPROP 2 LAST CDS_LIB pure_quanta
J 0
(3350 4700);
DISPLAY INVISIBLE (3350 4700);
FORCEPROP 1 LAST LOCATION R679
J 0
(3125 4700);
DISPLAY 0.702128 (3125 4700);
PAINT YELLOW (3125 4700);
FORCEPROP 0 LAST $SEC 1
J 0
(3125 4750);
DISPLAY 0.680851 (3125 4750);
PAINT MONO (3125 4750);
DISPLAY INVISIBLE (3125 4750);
FORCEPROP 0 LAST CDS_SEC 1
J 0
(3125 4750);
DISPLAY 1.021277 (3125 4750);
DISPLAY INVISIBLE (3125 4750);
FORCEPROP 1 LASTPIN (3250 4700) $PN 1
J 0
(3262 4712);
DISPLAY 0.808511 (3262 4712);
PAINT WHITE (3262 4712);
DISPLAY INVISIBLE (3262 4712);
FORCEPROP 1 LASTPIN (3450 4700) $PN 2
J 0
(3412 4712);
DISPLAY 0.808511 (3412 4712);
PAINT WHITE (3412 4712);
DISPLAY INVISIBLE (3412 4712);
FORCEADD Q_RES..1
(3350 4650);
FORCEPROP 1 LAST VALUE 33.2
J 2
(3575 4650);
DISPLAY 0.510638 (3575 4650);
PAINT SKYBLUE (3575 4650);
FORCEPROP 1 LAST MATERIAL EMPTY
J 0
(3600 4650);
DISPLAY 0.510638 (3600 4650);
PAINT RED (3600 4650);
FORCEPROP 1 LAST TOLERANCE 1%
J 0
(3275 4750);
DISPLAY 0.510638 (3275 4750);
PAINT SKYBLUE (3275 4750);
DISPLAY INVISIBLE (3275 4750);
FORCEPROP 1 LAST PART_NUMBER CS03322FB03
J 0
(3250 4725);
DISPLAY 0.510638 (3250 4725);
PAINT WHITE (3250 4725);
DISPLAY INVISIBLE (3250 4725);
FORCEPROP 1 LAST PACK_TYPE 0402LF
J 0
(3325 4700);
DISPLAY 0.510638 (3325 4700);
PAINT SKYBLUE (3325 4700);
DISPLAY INVISIBLE (3325 4700);
FORCEPROP 1 LAST WATTAGE 1/16W
J 2
(3700 4750);
DISPLAY 0.510638 (3700 4750);
PAINT SKYBLUE (3700 4750);
DISPLAY INVISIBLE (3700 4750);
FORCEPROP 1 LAST PATH I248
J 0
(3300 4800);
DISPLAY 0.978723 (3300 4800);
PAINT WHITE (3300 4800);
DISPLAY INVISIBLE (3300 4800);
FORCEPROP 2 LAST CDS_LIB pure_quanta
J 0
(3350 4650);
DISPLAY INVISIBLE (3350 4650);
FORCEPROP 1 LAST LOCATION R680
J 0
(3125 4650);
DISPLAY 0.702128 (3125 4650);
PAINT YELLOW (3125 4650);
FORCEPROP 0 LAST $SEC 1
J 0
(3125 4700);
DISPLAY 0.680851 (3125 4700);
PAINT MONO (3125 4700);
DISPLAY INVISIBLE (3125 4700);
FORCEPROP 0 LAST CDS_SEC 1
J 0
(3125 4700);
DISPLAY 1.021277 (3125 4700);
DISPLAY INVISIBLE (3125 4700);
FORCEPROP 1 LASTPIN (3250 4650) $PN 1
J 0
(3262 4662);
DISPLAY 0.808511 (3262 4662);
PAINT WHITE (3262 4662);
DISPLAY INVISIBLE (3262 4662);
FORCEPROP 1 LASTPIN (3450 4650) $PN 2
J 0
(3412 4662);
DISPLAY 0.808511 (3412 4662);
PAINT WHITE (3412 4662);
DISPLAY INVISIBLE (3412 4662);
FORCEADD OFFPAGE..2
R 2
(-2975 4275);
FORCEPROP 2 LAST $XR0 21 
J 0
(-3229 4275);
DISPLAY 0.638298 (-3229 4275);
PAINT MONO (-3229 4275);
FORCEPROP 2 LAST PATH I26
J 0
(-3175 4325);
DISPLAY 1.021277 (-3175 4325);
DISPLAY INVISIBLE (-3175 4325);
FORCEPROP 1 LAST COMMENT_BODY TRUE
J 2
(-2930 4180);
DISPLAY 0.872340 (-2930 4180);
PAINT PEACH (-2930 4180);
DISPLAY INVISIBLE (-2930 4180);
FORCEPROP 1 LAST OFFPAGE TRUE
J 2
(-3300 4150);
DISPLAY 0.872340 (-3300 4150);
PAINT GREEN (-3300 4150);
DISPLAY INVISIBLE (-3300 4150);
FORCEPROP 2 LAST CDS_LIB standard
J 0
(-2975 4275);
DISPLAY INVISIBLE (-2975 4275);
FORCEADD Q_RES..1
(3800 2825);
FORCEPROP 1 LAST MATERIAL CHIP
J 1
(4050 2825);
DISPLAY 0.510638 (4050 2825);
PAINT SKYBLUE (4050 2825);
FORCEPROP 1 LAST VALUE 33.2
J 1
(3950 2825);
DISPLAY 0.510638 (3950 2825);
PAINT SKYBLUE (3950 2825);
FORCEPROP 1 LAST TOLERANCE 1%
J 0
(3925 2825);
DISPLAY 0.510638 (3925 2825);
PAINT SKYBLUE (3925 2825);
DISPLAY INVISIBLE (3925 2825);
FORCEPROP 1 LAST PART_NUMBER CS03322FB03
J 0
(3750 2925);
DISPLAY 0.510638 (3750 2925);
PAINT WHITE (3750 2925);
DISPLAY INVISIBLE (3750 2925);
FORCEPROP 1 LAST PACK_TYPE 0402LF
J 0
(4050 2675);
DISPLAY 0.510638 (4050 2675);
PAINT SKYBLUE (4050 2675);
DISPLAY INVISIBLE (4050 2675);
FORCEPROP 1 LAST WATTAGE 1/16W
J 2
(3775 2675);
DISPLAY 0.510638 (3775 2675);
PAINT SKYBLUE (3775 2675);
DISPLAY INVISIBLE (3775 2675);
FORCEPROP 1 LAST PATH I266
J 0
(3750 2975);
DISPLAY 0.978723 (3750 2975);
PAINT WHITE (3750 2975);
DISPLAY INVISIBLE (3750 2975);
FORCEPROP 2 LAST SEC_TYPE 0402LF
J 0
(3750 3025);
DISPLAY 0.680851 (3750 3025);
DISPLAY INVISIBLE (3750 3025);
FORCEPROP 2 LAST CDS_LIB pure_quanta
J 0
(3800 2825);
DISPLAY INVISIBLE (3800 2825);
FORCEPROP 1 LAST LOCATION R111
J 2
(3700 2825);
DISPLAY 0.702128 (3700 2825);
PAINT YELLOW (3700 2825);
FORCEPROP 1 LASTPIN (3700 2825) $PN 1
J 0
(3712 2837);
DISPLAY 0.808511 (3712 2837);
PAINT WHITE (3712 2837);
FORCEPROP 1 LASTPIN (3900 2825) $PN 2
J 0
(3862 2837);
DISPLAY 0.808511 (3862 2837);
PAINT WHITE (3862 2837);
FORCEPROP 0 LAST SEC 1
J 0
(3550 2875);
DISPLAY 0.680851 (3550 2875);
PAINT MONO (3550 2875);
DISPLAY INVISIBLE (3550 2875);
FORCEADD OFFPAGE..2
R 2
(-2975 4325);
FORCEPROP 2 LAST $XR0 21 
J 0
(-3229 4325);
DISPLAY 0.638298 (-3229 4325);
PAINT MONO (-3229 4325);
FORCEPROP 2 LAST PATH I27
J 0
(-3175 4375);
DISPLAY 1.021277 (-3175 4375);
DISPLAY INVISIBLE (-3175 4375);
FORCEPROP 1 LAST COMMENT_BODY TRUE
J 2
(-2930 4230);
DISPLAY 0.872340 (-2930 4230);
PAINT PEACH (-2930 4230);
DISPLAY INVISIBLE (-2930 4230);
FORCEPROP 1 LAST OFFPAGE TRUE
J 2
(-3300 4200);
DISPLAY 0.872340 (-3300 4200);
PAINT GREEN (-3300 4200);
DISPLAY INVISIBLE (-3300 4200);
FORCEPROP 2 LAST CDS_LIB standard
J 0
(-2975 4325);
DISPLAY INVISIBLE (-2975 4325);
FORCEADD OFFPAGE..2
(4275 -600);
FORCEPROP 2 LAST $XR0 13 
J 0
(4464 -600);
DISPLAY 0.638298 (4464 -600);
PAINT MONO (4464 -600);
FORCEPROP 2 LAST PATH I274
J 0
(4475 -550);
DISPLAY 0.680851 (4475 -550);
DISPLAY INVISIBLE (4475 -550);
FORCEPROP 1 LAST COMMENT_BODY TRUE
J 0
(4230 -695);
DISPLAY 0.872340 (4230 -695);
PAINT PEACH (4230 -695);
DISPLAY INVISIBLE (4230 -695);
FORCEPROP 1 LAST OFFPAGE TRUE
J 0
(4600 -725);
DISPLAY 0.872340 (4600 -725);
PAINT GREEN (4600 -725);
DISPLAY INVISIBLE (4600 -725);
FORCEPROP 2 LAST CDS_LIB standard
J 0
(4275 -600);
DISPLAY INVISIBLE (4275 -600);
FORCEADD OFFPAGE..2
(4275 -650);
FORCEPROP 2 LAST $XR0 13 
J 0
(4464 -650);
DISPLAY 0.638298 (4464 -650);
PAINT MONO (4464 -650);
FORCEPROP 2 LAST PATH I275
J 0
(4475 -600);
DISPLAY 0.680851 (4475 -600);
DISPLAY INVISIBLE (4475 -600);
FORCEPROP 1 LAST COMMENT_BODY TRUE
J 0
(4230 -745);
DISPLAY 0.872340 (4230 -745);
PAINT PEACH (4230 -745);
DISPLAY INVISIBLE (4230 -745);
FORCEPROP 1 LAST OFFPAGE TRUE
J 0
(4600 -775);
DISPLAY 0.872340 (4600 -775);
PAINT GREEN (4600 -775);
DISPLAY INVISIBLE (4600 -775);
FORCEPROP 2 LAST CDS_LIB standard
J 0
(4275 -650);
DISPLAY INVISIBLE (4275 -650);
FORCEADD Q_RES..1
(2800 -600);
FORCEPROP 1 LAST VALUE 4.7K
J 2
(3075 -600);
DISPLAY 0.510638 (3075 -600);
PAINT SKYBLUE (3075 -600);
FORCEPROP 1 LAST MATERIAL CHIP
J 0
(3175 -600);
DISPLAY 0.510638 (3175 -600);
PAINT SKYBLUE (3175 -600);
FORCEPROP 1 LAST PART_NUMBER CS24702FB06
J 0
(2750 -500);
DISPLAY 0.510638 (2750 -500);
PAINT WHITE (2750 -500);
DISPLAY INVISIBLE (2750 -500);
FORCEPROP 1 LAST PACK_TYPE 0402LF
J 0
(3050 -750);
DISPLAY 0.510638 (3050 -750);
PAINT SKYBLUE (3050 -750);
DISPLAY INVISIBLE (3050 -750);
FORCEPROP 1 LAST WATTAGE 1/16W
J 2
(2775 -750);
DISPLAY 0.510638 (2775 -750);
PAINT SKYBLUE (2775 -750);
DISPLAY INVISIBLE (2775 -750);
FORCEPROP 1 LAST PATH I278
J 0
(2750 -450);
DISPLAY 0.978723 (2750 -450);
PAINT WHITE (2750 -450);
DISPLAY INVISIBLE (2750 -450);
FORCEPROP 1 LAST TOLERANCE 1%
J 0
(2800 -700);
DISPLAY 0.510638 (2800 -700);
PAINT SKYBLUE (2800 -700);
DISPLAY INVISIBLE (2800 -700);
FORCEPROP 2 LAST SEC_TYPE 0402LF
J 0
(2750 -400);
DISPLAY 0.680851 (2750 -400);
DISPLAY INVISIBLE (2750 -400);
FORCEPROP 2 LAST CDS_LIB pure_quanta
J 0
(2800 -600);
DISPLAY INVISIBLE (2800 -600);
FORCEPROP 1 LAST LOCATION R55
J 2
(2650 -600);
DISPLAY 0.702128 (2650 -600);
PAINT YELLOW (2650 -600);
FORCEPROP 1 LASTPIN (2700 -600) $PN 1
J 0
(2712 -588);
DISPLAY 0.808511 (2712 -588);
PAINT WHITE (2712 -588);
FORCEPROP 1 LASTPIN (2900 -600) $PN 2
J 0
(2862 -588);
DISPLAY 0.808511 (2862 -588);
PAINT WHITE (2862 -588);
FORCEPROP 2 LAST SEC 1
J 0
(2750 -400);
DISPLAY 0.680851 (2750 -400);
PAINT MONO (2750 -400);
DISPLAY INVISIBLE (2750 -400);
FORCEADD Q_RES..1
(2800 -650);
FORCEPROP 1 LAST VALUE 4.7K
J 2
(3075 -650);
DISPLAY 0.510638 (3075 -650);
PAINT SKYBLUE (3075 -650);
FORCEPROP 1 LAST MATERIAL CHIP
J 0
(3175 -650);
DISPLAY 0.510638 (3175 -650);
PAINT SKYBLUE (3175 -650);
FORCEPROP 1 LAST PART_NUMBER CS24702FB06
J 0
(2750 -550);
DISPLAY 0.510638 (2750 -550);
PAINT WHITE (2750 -550);
DISPLAY INVISIBLE (2750 -550);
FORCEPROP 1 LAST PACK_TYPE 0402LF
J 0
(3050 -800);
DISPLAY 0.510638 (3050 -800);
PAINT SKYBLUE (3050 -800);
DISPLAY INVISIBLE (3050 -800);
FORCEPROP 1 LAST WATTAGE 1/16W
J 2
(2775 -800);
DISPLAY 0.510638 (2775 -800);
PAINT SKYBLUE (2775 -800);
DISPLAY INVISIBLE (2775 -800);
FORCEPROP 1 LAST PATH I279
J 0
(2750 -500);
DISPLAY 0.978723 (2750 -500);
PAINT WHITE (2750 -500);
DISPLAY INVISIBLE (2750 -500);
FORCEPROP 1 LAST TOLERANCE 1%
J 0
(2800 -750);
DISPLAY 0.510638 (2800 -750);
PAINT SKYBLUE (2800 -750);
DISPLAY INVISIBLE (2800 -750);
FORCEPROP 2 LAST SEC_TYPE 0402LF
J 0
(2750 -450);
DISPLAY 0.680851 (2750 -450);
DISPLAY INVISIBLE (2750 -450);
FORCEPROP 2 LAST CDS_LIB pure_quanta
J 0
(2800 -650);
DISPLAY INVISIBLE (2800 -650);
FORCEPROP 1 LAST LOCATION R56
J 2
(2650 -650);
DISPLAY 0.702128 (2650 -650);
PAINT YELLOW (2650 -650);
FORCEPROP 1 LASTPIN (2700 -650) $PN 1
J 0
(2712 -638);
DISPLAY 0.808511 (2712 -638);
PAINT WHITE (2712 -638);
FORCEPROP 1 LASTPIN (2900 -650) $PN 2
J 0
(2862 -638);
DISPLAY 0.808511 (2862 -638);
PAINT WHITE (2862 -638);
FORCEPROP 2 LAST SEC 1
J 0
(2750 -450);
DISPLAY 0.680851 (2750 -450);
PAINT MONO (2750 -450);
DISPLAY INVISIBLE (2750 -450);
FORCEADD UNIVERSAL_GND..1
(-1650 -425);
FORCEPROP 3 LASTPIN (-1650 -375) SIG_NAME GND\g
J 0
(-1640 -365);
DISPLAY 0.659574 (-1640 -365);
PAINT MONO (-1640 -365);
DISPLAY INVISIBLE (-1640 -365);
FORCEPROP 2 LAST CDS_LIB logical_power
J 0
(-1650 -425);
DISPLAY INVISIBLE (-1650 -425);
FORCEPROP 1 LAST PATH I28
J 0
(-1575 -425);
DISPLAY 0.872340 (-1575 -425);
PAINT AQUA (-1575 -425);
DISPLAY INVISIBLE (-1575 -425);
FORCEPROP 1 LAST HDL_POWER GND
J 1
(-1625 -500);
DISPLAY 0.702128 (-1625 -500);
PAINT GREEN (-1625 -500);
DISPLAY INVISIBLE (-1625 -500);
FORCEADD UNIVERSAL_POWER..1
(2475 -400);
FORCEPROP 3 LASTPIN (2475 -450) SIG_NAME P3V3_AUX\g
J 0
(2485 -440);
DISPLAY 0.659574 (2485 -440);
PAINT MONO (2485 -440);
DISPLAY INVISIBLE (2485 -440);
FORCEPROP 1 LAST HDL_POWER P3V3_AUX
J 1
(2475 -350);
DISPLAY 0.702128 (2475 -350);
PAINT GREEN (2475 -350);
FORCEPROP 1 LAST PATH I282
J 0
(2525 -375);
DISPLAY 0.872340 (2525 -375);
PAINT AQUA (2525 -375);
DISPLAY INVISIBLE (2525 -375);
FORCEPROP 2 LAST CDS_LIB logical_power
J 0
(2475 -400);
DISPLAY INVISIBLE (2475 -400);
FORCEADD OFFPAGE..3
(4475 3525);
FORCEPROP 2 LAST $XR0 44 
J 0
(4689 3525);
DISPLAY 0.638298 (4689 3525);
PAINT MONO (4689 3525);
FORCEPROP 2 LAST CDS_LIB standard
J 0
(4475 3525);
DISPLAY INVISIBLE (4475 3525);
FORCEPROP 2 LAST PATH I283
J 0
(4700 3575);
DISPLAY 0.680851 (4700 3575);
DISPLAY INVISIBLE (4700 3575);
FORCEPROP 1 LAST COMMENT_BODY TRUE
J 0
(4425 3425);
DISPLAY 0.872340 (4425 3425);
PAINT PEACH (4425 3425);
DISPLAY INVISIBLE (4425 3425);
FORCEPROP 1 LAST OFFPAGE TRUE
J 0
(4800 3400);
DISPLAY 0.872340 (4800 3400);
PAINT GREEN (4800 3400);
DISPLAY INVISIBLE (4800 3400);
FORCEADD OFFPAGE..2
(4925 3025);
FORCEPROP 2 LAST $XR0 21 
J 0
(5114 3025);
DISPLAY 0.638298 (5114 3025);
PAINT MONO (5114 3025);
FORCEPROP 2 LAST PATH I284
J 0
(5125 3075);
DISPLAY 0.680851 (5125 3075);
DISPLAY INVISIBLE (5125 3075);
FORCEPROP 1 LAST COMMENT_BODY TRUE
J 0
(4880 2930);
DISPLAY 0.872340 (4880 2930);
PAINT GREEN (4880 2930);
DISPLAY INVISIBLE (4880 2930);
FORCEPROP 1 LAST OFFPAGE TRUE
J 0
(5250 2900);
DISPLAY 0.872340 (5250 2900);
DISPLAY INVISIBLE (5250 2900);
FORCEPROP 2 LAST CDS_LIB standard
J 0
(4925 3025);
DISPLAY INVISIBLE (4925 3025);
FORCEADD Q_RES..1
(3650 3025);
FORCEPROP 1 LAST MATERIAL CHIP
J 1
(3950 3025);
DISPLAY 0.510638 (3950 3025);
PAINT SKYBLUE (3950 3025);
FORCEPROP 1 LAST VALUE 33.2
J 1
(3825 3025);
DISPLAY 0.510638 (3825 3025);
PAINT SKYBLUE (3825 3025);
FORCEPROP 1 LAST WATTAGE 1/16W
J 2
(4050 2975);
DISPLAY 0.510638 (4050 2975);
PAINT SKYBLUE (4050 2975);
DISPLAY INVISIBLE (4050 2975);
FORCEPROP 1 LAST TOLERANCE 1%
J 0
(3875 2975);
DISPLAY 0.510638 (3875 2975);
PAINT SKYBLUE (3875 2975);
DISPLAY INVISIBLE (3875 2975);
FORCEPROP 1 LAST PACK_TYPE 0402LF
J 0
(3700 2975);
DISPLAY 0.510638 (3700 2975);
PAINT SKYBLUE (3700 2975);
DISPLAY INVISIBLE (3700 2975);
FORCEPROP 2 LAST CDS_LIB pure_quanta
J 0
(3650 3025);
DISPLAY INVISIBLE (3650 3025);
FORCEPROP 2 LAST SEC_TYPE 0402LF
J 0
(3600 3225);
DISPLAY 0.680851 (3600 3225);
DISPLAY INVISIBLE (3600 3225);
FORCEPROP 1 LAST PATH I286
J 0
(3600 3175);
DISPLAY 0.978723 (3600 3175);
PAINT WHITE (3600 3175);
DISPLAY INVISIBLE (3600 3175);
FORCEPROP 1 LAST PART_NUMBER CS03322FB03
J 0
(3775 3075);
DISPLAY 0.510638 (3775 3075);
PAINT WHITE (3775 3075);
DISPLAY INVISIBLE (3775 3075);
FORCEPROP 1 LAST LOCATION R96
J 2
(3550 3025);
DISPLAY 0.702128 (3550 3025);
PAINT YELLOW (3550 3025);
FORCEPROP 1 LASTPIN (3550 3025) $PN 1
J 0
(3562 3037);
DISPLAY 0.808511 (3562 3037);
PAINT WHITE (3562 3037);
FORCEPROP 1 LASTPIN (3750 3025) $PN 2
J 0
(3715 3035);
DISPLAY 0.808511 (3715 3035);
PAINT WHITE (3715 3035);
FORCEPROP 2 LAST SEC 1
J 0
(3600 3225);
DISPLAY 0.680851 (3600 3225);
PAINT MONO (3600 3225);
DISPLAY INVISIBLE (3600 3225);
FORCEADD OFFPAGE..5
R 2
(3900 2475);
FORCEPROP 2 LAST $XR0 13 
J 0
(4089 2475);
DISPLAY 0.638298 (4089 2475);
PAINT MONO (4089 2475);
FORCEPROP 2 LAST PATH I289
J 0
(4100 2525);
DISPLAY 0.680851 (4100 2525);
DISPLAY INVISIBLE (4100 2525);
FORCEPROP 1 LAST COMMENT_BODY TRUE
J 2
(3800 2400);
DISPLAY 0.872340 (3800 2400);
PAINT PEACH (3800 2400);
DISPLAY INVISIBLE (3800 2400);
FORCEPROP 1 LAST OFFPAGE TRUE
J 2
(3575 2350);
DISPLAY 0.872340 (3575 2350);
PAINT GREEN (3575 2350);
DISPLAY INVISIBLE (3575 2350);
FORCEPROP 2 LAST CDS_LIB standard
J 0
(3900 2475);
DISPLAY INVISIBLE (3900 2475);
FORCEADD Q_CAP..1
(-1950 -150);
FORCEPROP 1 LAST VALUE 1UF
J 0
(-1900 -100);
DISPLAY 0.510638 (-1900 -100);
PAINT SKYBLUE (-1900 -100);
FORCEPROP 1 LAST VOLTAGE 25V
J 0
(-1900 -150);
DISPLAY 0.510638 (-1900 -150);
PAINT SKYBLUE (-1900 -150);
FORCEPROP 1 LAST MATERIAL X6S
J 0
(-1900 -250);
DISPLAY 0.510638 (-1900 -250);
PAINT SKYBLUE (-1900 -250);
FORCEPROP 1 LAST PACK_TYPE C0402
J 0
(-1925 -300);
DISPLAY 0.510638 (-1925 -300);
PAINT SKYBLUE (-1925 -300);
FORCEPROP 1 LAST TOLERANCE 10%
J 0
(-1900 -200);
DISPLAY 0.510638 (-1900 -200);
PAINT SKYBLUE (-1900 -200);
FORCEPROP 1 LAST PATH I29
J 0
(-1900 0);
DISPLAY 0.978723 (-1900 0);
PAINT WHITE (-1900 0);
DISPLAY INVISIBLE (-1900 0);
FORCEPROP 1 LAST PART_NUMBER CH5104KEB02
J 0
(-1950 -375);
DISPLAY 0.510638 (-1950 -375);
PAINT WHITE (-1950 -375);
DISPLAY INVISIBLE (-1950 -375);
FORCEPROP 2 LAST CDS_LIB pure_quanta
J 0
(-1950 -150);
DISPLAY INVISIBLE (-1950 -150);
FORCEPROP 1 LAST LOCATION C30
J 0
(-1900 -50);
DISPLAY 0.702128 (-1900 -50);
PAINT YELLOW (-1900 -50);
FORCEPROP 1 LASTPIN (-1950 -50) $PN 1
J 0
(-1940 -70);
DISPLAY 0.808511 (-1940 -70);
PAINT WHITE (-1940 -70);
FORCEPROP 1 LASTPIN (-1950 -250) $PN 2
J 0
(-1940 -270);
DISPLAY 0.808511 (-1940 -270);
PAINT WHITE (-1940 -270);
FORCEPROP 0 LAST $SEC 1
J 0
(-1900 0);
DISPLAY 0.680851 (-1900 0);
PAINT MONO (-1900 0);
DISPLAY INVISIBLE (-1900 0);
FORCEPROP 0 LAST CDS_SEC 1
J 0
(-1900 0);
DISPLAY 0.680851 (-1900 0);
DISPLAY INVISIBLE (-1900 0);
FORCEADD OFFPAGE..2
(4925 2825);
FORCEPROP 2 LAST $XR0 35 
J 0
(5114 2825);
DISPLAY 0.638298 (5114 2825);
PAINT MONO (5114 2825);
FORCEPROP 2 LAST PATH I290
J 0
(5125 2875);
DISPLAY 0.680851 (5125 2875);
DISPLAY INVISIBLE (5125 2875);
FORCEPROP 1 LAST COMMENT_BODY TRUE
J 0
(4880 2730);
DISPLAY 0.872340 (4880 2730);
PAINT PEACH (4880 2730);
DISPLAY INVISIBLE (4880 2730);
FORCEPROP 1 LAST OFFPAGE TRUE
J 0
(5250 2700);
DISPLAY 0.872340 (5250 2700);
PAINT GREEN (5250 2700);
DISPLAY INVISIBLE (5250 2700);
FORCEPROP 2 LAST CDS_LIB standard
J 0
(4925 2825);
DISPLAY INVISIBLE (4925 2825);
FORCEADD Q_RES..1
(-2300 2275);
FORCEPROP 1 LAST VALUE 33.2
J 0
(-2200 2275);
DISPLAY 0.510638 (-2200 2275);
PAINT SKYBLUE (-2200 2275);
FORCEPROP 1 LAST MATERIAL CHIP
J 0
(-2100 2275);
DISPLAY 0.510638 (-2100 2275);
PAINT SKYBLUE (-2100 2275);
FORCEPROP 1 LAST TOLERANCE 1%
J 0
(-2175 2275);
DISPLAY 0.510638 (-2175 2275);
PAINT SKYBLUE (-2175 2275);
DISPLAY INVISIBLE (-2175 2275);
FORCEPROP 1 LAST PART_NUMBER CS03322FB03
J 0
(-2350 2375);
DISPLAY 0.510638 (-2350 2375);
PAINT WHITE (-2350 2375);
DISPLAY INVISIBLE (-2350 2375);
FORCEPROP 1 LAST PACK_TYPE 0402LF
J 0
(-2050 2125);
DISPLAY 0.510638 (-2050 2125);
PAINT SKYBLUE (-2050 2125);
DISPLAY INVISIBLE (-2050 2125);
FORCEPROP 1 LAST WATTAGE 1/16W
J 2
(-2325 2125);
DISPLAY 0.510638 (-2325 2125);
PAINT SKYBLUE (-2325 2125);
DISPLAY INVISIBLE (-2325 2125);
FORCEPROP 1 LAST PATH I295
J 0
(-2350 2425);
DISPLAY 0.978723 (-2350 2425);
PAINT WHITE (-2350 2425);
DISPLAY INVISIBLE (-2350 2425);
FORCEPROP 2 LAST CDS_LIB pure_quanta
J 0
(-2300 2275);
DISPLAY INVISIBLE (-2300 2275);
FORCEPROP 1 LAST LOCATION R840
J 0
(-2525 2275);
DISPLAY 0.702128 (-2525 2275);
PAINT YELLOW (-2525 2275);
FORCEPROP 1 LASTPIN (-2400 2275) $PN 1
J 0
(-2388 2287);
DISPLAY 0.808511 (-2388 2287);
PAINT WHITE (-2388 2287);
FORCEPROP 1 LASTPIN (-2200 2275) $PN 2
J 0
(-2238 2287);
DISPLAY 0.808511 (-2238 2287);
PAINT WHITE (-2238 2287);
FORCEPROP 0 LAST $SEC 1
J 0
(-2350 2375);
DISPLAY 0.680851 (-2350 2375);
PAINT MONO (-2350 2375);
DISPLAY INVISIBLE (-2350 2375);
FORCEPROP 0 LAST CDS_SEC 1
J 0
(-2350 2375);
DISPLAY 0.680851 (-2350 2375);
DISPLAY INVISIBLE (-2350 2375);
FORCEADD OFFPAGE..1
(-3425 2275);
FORCEPROP 2 LAST $XR3 35 
J 0
(-3946 2275);
DISPLAY 0.638298 (-3946 2275);
PAINT MONO (-3946 2275);
FORCEPROP 2 LAST $XR2 28 
J 0
(-3856 2275);
DISPLAY 0.638298 (-3856 2275);
PAINT MONO (-3856 2275);
FORCEPROP 2 LAST $XR1 11 
J 0
(-3766 2275);
DISPLAY 0.638298 (-3766 2275);
PAINT MONO (-3766 2275);
FORCEPROP 2 LAST $XR0 10 
J 0
(-3676 2275);
DISPLAY 0.638298 (-3676 2275);
PAINT MONO (-3676 2275);
FORCEPROP 2 LAST PATH I296
J 0
(-3675 2325);
DISPLAY 0.680851 (-3675 2325);
DISPLAY INVISIBLE (-3675 2325);
FORCEPROP 1 LAST COMMENT_BODY TRUE
J 0
(-3300 2175);
DISPLAY 0.872340 (-3300 2175);
PAINT PEACH (-3300 2175);
DISPLAY INVISIBLE (-3300 2175);
FORCEPROP 1 LAST OFFPAGE TRUE
J 0
(-3100 2150);
DISPLAY 0.872340 (-3100 2150);
PAINT GREEN (-3100 2150);
DISPLAY INVISIBLE (-3100 2150);
FORCEPROP 2 LAST CDS_LIB standard
J 0
(-3425 2275);
DISPLAY INVISIBLE (-3425 2275);
FORCEADD OFFPAGE..5
(-3425 2325);
FORCEPROP 2 LAST $XR1 35 
J 0
(-3769 2325);
DISPLAY 0.638298 (-3769 2325);
PAINT MONO (-3769 2325);
FORCEPROP 2 LAST $XR0 13 
J 0
(-3679 2325);
DISPLAY 0.638298 (-3679 2325);
PAINT MONO (-3679 2325);
FORCEPROP 2 LAST PATH I297
J 0
(-3675 2375);
DISPLAY 0.680851 (-3675 2375);
DISPLAY INVISIBLE (-3675 2375);
FORCEPROP 1 LAST COMMENT_BODY TRUE
J 0
(-3325 2250);
DISPLAY 0.872340 (-3325 2250);
PAINT PEACH (-3325 2250);
DISPLAY INVISIBLE (-3325 2250);
FORCEPROP 1 LAST OFFPAGE TRUE
J 0
(-3100 2200);
DISPLAY 0.872340 (-3100 2200);
PAINT GREEN (-3100 2200);
DISPLAY INVISIBLE (-3100 2200);
FORCEPROP 2 LAST CDS_LIB standard
J 0
(-3425 2325);
DISPLAY INVISIBLE (-3425 2325);
FORCEADD OFFPAGE..2
(4275 -850);
FORCEPROP 2 LAST $XR1 35 
J 0
(4554 -850);
DISPLAY 0.638298 (4554 -850);
PAINT MONO (4554 -850);
FORCEPROP 2 LAST $XR0 13 
J 0
(4464 -850);
DISPLAY 0.638298 (4464 -850);
PAINT MONO (4464 -850);
FORCEPROP 2 LAST PATH I298
J 0
(4475 -800);
DISPLAY 0.680851 (4475 -800);
DISPLAY INVISIBLE (4475 -800);
FORCEPROP 1 LAST COMMENT_BODY TRUE
J 0
(4230 -945);
DISPLAY 0.872340 (4230 -945);
PAINT PEACH (4230 -945);
DISPLAY INVISIBLE (4230 -945);
FORCEPROP 1 LAST OFFPAGE TRUE
J 0
(4600 -975);
DISPLAY 0.872340 (4600 -975);
PAINT GREEN (4600 -975);
DISPLAY INVISIBLE (4600 -975);
FORCEPROP 2 LAST CDS_LIB standard
J 0
(4275 -850);
DISPLAY INVISIBLE (4275 -850);
FORCEADD Q_RES..1
(2800 -850);
FORCEPROP 1 LAST MATERIAL CHIP
J 0
(3175 -850);
DISPLAY 0.510638 (3175 -850);
PAINT SKYBLUE (3175 -850);
FORCEPROP 1 LAST VALUE 4.7K
J 2
(3075 -850);
DISPLAY 0.510638 (3075 -850);
PAINT SKYBLUE (3075 -850);
FORCEPROP 1 LAST PART_NUMBER CS24702FB06
J 0
(2750 -750);
DISPLAY 0.510638 (2750 -750);
PAINT WHITE (2750 -750);
DISPLAY INVISIBLE (2750 -750);
FORCEPROP 1 LAST PACK_TYPE 0402LF
J 0
(3050 -1000);
DISPLAY 0.510638 (3050 -1000);
PAINT SKYBLUE (3050 -1000);
DISPLAY INVISIBLE (3050 -1000);
FORCEPROP 1 LAST WATTAGE 1/16W
J 2
(2775 -1000);
DISPLAY 0.510638 (2775 -1000);
PAINT SKYBLUE (2775 -1000);
DISPLAY INVISIBLE (2775 -1000);
FORCEPROP 1 LAST PATH I299
J 0
(2750 -700);
DISPLAY 0.978723 (2750 -700);
PAINT WHITE (2750 -700);
DISPLAY INVISIBLE (2750 -700);
FORCEPROP 1 LAST TOLERANCE 1%
J 0
(2800 -950);
DISPLAY 0.510638 (2800 -950);
PAINT SKYBLUE (2800 -950);
DISPLAY INVISIBLE (2800 -950);
FORCEPROP 2 LAST SEC_TYPE 0402LF
J 0
(2750 -650);
DISPLAY 0.680851 (2750 -650);
DISPLAY INVISIBLE (2750 -650);
FORCEPROP 2 LAST CDS_LIB pure_quanta
J 0
(2800 -850);
DISPLAY INVISIBLE (2800 -850);
FORCEPROP 1 LAST LOCATION R446
J 2
(2650 -850);
DISPLAY 0.702128 (2650 -850);
PAINT YELLOW (2650 -850);
FORCEPROP 1 LASTPIN (2700 -850) $PN 1
J 0
(2712 -838);
DISPLAY 0.808511 (2712 -838);
PAINT WHITE (2712 -838);
FORCEPROP 1 LASTPIN (2900 -850) $PN 2
J 0
(2862 -838);
DISPLAY 0.808511 (2862 -838);
PAINT WHITE (2862 -838);
FORCEPROP 2 LAST SEC 1
J 0
(2750 -650);
DISPLAY 0.680851 (2750 -650);
PAINT MONO (2750 -650);
DISPLAY INVISIBLE (2750 -650);
FORCEADD Q_RES..1
(-2875 -650);
FORCEPROP 1 LAST MATERIAL EMPTY
J 0
(-2600 -650);
DISPLAY 0.510638 (-2600 -650);
PAINT RED (-2600 -650);
FORCEPROP 1 LAST VALUE 0
J 2
(-2675 -650);
DISPLAY 0.510638 (-2675 -650);
PAINT SKYBLUE (-2675 -650);
FORCEPROP 1 LAST PART_NUMBER CS00002JB13
J 0
(-2875 -475);
DISPLAY 0.510638 (-2875 -475);
PAINT WHITE (-2875 -475);
DISPLAY INVISIBLE (-2875 -475);
FORCEPROP 1 LAST PACK_TYPE 0402LF
J 0
(-2675 -550);
DISPLAY 0.510638 (-2675 -550);
PAINT SKYBLUE (-2675 -550);
DISPLAY INVISIBLE (-2675 -550);
FORCEPROP 1 LAST WATTAGE 1/16W
J 2
(-2700 -550);
DISPLAY 0.510638 (-2700 -550);
PAINT SKYBLUE (-2700 -550);
DISPLAY INVISIBLE (-2700 -550);
FORCEPROP 1 LAST PATH I3
J 0
(-2925 -500);
DISPLAY 0.978723 (-2925 -500);
PAINT WHITE (-2925 -500);
DISPLAY INVISIBLE (-2925 -500);
FORCEPROP 1 LAST TOLERANCE 5%
J 0
(-2375 -550);
DISPLAY 0.510638 (-2375 -550);
PAINT SKYBLUE (-2375 -550);
DISPLAY INVISIBLE (-2375 -550);
FORCEPROP 2 LAST CDS_LIB pure_quanta
J 0
(-2875 -650);
DISPLAY INVISIBLE (-2875 -650);
FORCEPROP 1 LAST LOCATION R154
J 0
(-3225 -650);
DISPLAY 0.702128 (-3225 -650);
PAINT YELLOW (-3225 -650);
FORCEPROP 1 LASTPIN (-2975 -650) $PN 1
J 0
(-2963 -638);
DISPLAY 0.808511 (-2963 -638);
PAINT WHITE (-2963 -638);
FORCEPROP 1 LASTPIN (-2775 -650) $PN 2
J 0
(-2813 -638);
DISPLAY 0.808511 (-2813 -638);
PAINT WHITE (-2813 -638);
FORCEPROP 0 LAST $SEC 1
J 0
(-2925 -550);
DISPLAY 0.680851 (-2925 -550);
PAINT MONO (-2925 -550);
DISPLAY INVISIBLE (-2925 -550);
FORCEPROP 0 LAST CDS_SEC 1
J 0
(-2925 -550);
DISPLAY 0.680851 (-2925 -550);
DISPLAY INVISIBLE (-2925 -550);
FORCEADD Q_CAP..1
(-1750 -150);
FORCEPROP 1 LAST TOLERANCE 10%
J 0
(-1700 -200);
DISPLAY 0.510638 (-1700 -200);
PAINT SKYBLUE (-1700 -200);
FORCEPROP 1 LAST MATERIAL X7R
J 0
(-1700 -250);
DISPLAY 0.510638 (-1700 -250);
PAINT SKYBLUE (-1700 -250);
FORCEPROP 1 LAST PACK_TYPE 0402
J 0
(-1700 -300);
DISPLAY 0.510638 (-1700 -300);
PAINT SKYBLUE (-1700 -300);
FORCEPROP 1 LAST VOLTAGE 25V
J 0
(-1700 -150);
DISPLAY 0.510638 (-1700 -150);
PAINT SKYBLUE (-1700 -150);
FORCEPROP 1 LAST VALUE 0.1UF
J 0
(-1700 -100);
DISPLAY 0.510638 (-1700 -100);
PAINT SKYBLUE (-1700 -100);
FORCEPROP 1 LAST PATH I30
J 0
(-1700 0);
DISPLAY 0.978723 (-1700 0);
PAINT WHITE (-1700 0);
DISPLAY INVISIBLE (-1700 0);
FORCEPROP 1 LAST PART_NUMBER CH4104K1B00
J 0
(-1700 -300);
DISPLAY 0.510638 (-1700 -300);
PAINT WHITE (-1700 -300);
DISPLAY INVISIBLE (-1700 -300);
FORCEPROP 2 LAST CDS_LIB pure_quanta
J 0
(-1750 -150);
DISPLAY INVISIBLE (-1750 -150);
FORCEPROP 1 LAST LOCATION C31
J 0
(-1700 -50);
DISPLAY 0.702128 (-1700 -50);
PAINT YELLOW (-1700 -50);
FORCEPROP 1 LASTPIN (-1750 -50) $PN 1
J 0
(-1740 -70);
DISPLAY 0.808511 (-1740 -70);
PAINT WHITE (-1740 -70);
FORCEPROP 1 LASTPIN (-1750 -250) $PN 2
J 0
(-1740 -270);
DISPLAY 0.808511 (-1740 -270);
PAINT WHITE (-1740 -270);
FORCEPROP 0 LAST $SEC 1
J 0
(-1700 0);
DISPLAY 0.680851 (-1700 0);
PAINT MONO (-1700 0);
DISPLAY INVISIBLE (-1700 0);
FORCEPROP 0 LAST CDS_SEC 1
J 0
(-1700 0);
DISPLAY 0.680851 (-1700 0);
DISPLAY INVISIBLE (-1700 0);
FORCEADD Q_RES..1
(-1750 3225);
FORCEPROP 1 LAST MATERIAL CHIP
J 0
(-1550 3225);
DISPLAY 0.510638 (-1550 3225);
PAINT SKYBLUE (-1550 3225);
FORCEPROP 1 LAST VALUE 33.2
J 0
(-1650 3225);
DISPLAY 0.510638 (-1650 3225);
PAINT SKYBLUE (-1650 3225);
FORCEPROP 1 LAST TOLERANCE 1%
J 0
(-1625 3225);
DISPLAY 0.510638 (-1625 3225);
PAINT SKYBLUE (-1625 3225);
DISPLAY INVISIBLE (-1625 3225);
FORCEPROP 1 LAST PART_NUMBER CS03322FB03
J 0
(-1800 3325);
DISPLAY 0.510638 (-1800 3325);
PAINT WHITE (-1800 3325);
DISPLAY INVISIBLE (-1800 3325);
FORCEPROP 1 LAST PACK_TYPE 0402LF
J 0
(-1500 3075);
DISPLAY 0.510638 (-1500 3075);
PAINT SKYBLUE (-1500 3075);
DISPLAY INVISIBLE (-1500 3075);
FORCEPROP 1 LAST WATTAGE 1/16W
J 2
(-1775 3075);
DISPLAY 0.510638 (-1775 3075);
PAINT SKYBLUE (-1775 3075);
DISPLAY INVISIBLE (-1775 3075);
FORCEPROP 1 LAST PATH I300
J 0
(-1800 3375);
DISPLAY 0.978723 (-1800 3375);
PAINT WHITE (-1800 3375);
DISPLAY INVISIBLE (-1800 3375);
FORCEPROP 2 LAST CDS_LIB pure_quanta
J 0
(-1750 3225);
DISPLAY INVISIBLE (-1750 3225);
FORCEPROP 1 LAST LOCATION R443
J 0
(-1975 3225);
DISPLAY 0.702128 (-1975 3225);
PAINT YELLOW (-1975 3225);
FORCEPROP 1 LASTPIN (-1850 3225) $PN 1
J 0
(-1838 3237);
DISPLAY 0.808511 (-1838 3237);
PAINT WHITE (-1838 3237);
FORCEPROP 1 LASTPIN (-1650 3225) $PN 2
J 0
(-1688 3237);
DISPLAY 0.808511 (-1688 3237);
PAINT WHITE (-1688 3237);
FORCEPROP 0 LAST $SEC 1
J 0
(-1800 3325);
DISPLAY 0.680851 (-1800 3325);
PAINT MONO (-1800 3325);
DISPLAY INVISIBLE (-1800 3325);
FORCEPROP 0 LAST CDS_SEC 1
J 0
(-1800 3325);
DISPLAY 0.680851 (-1800 3325);
DISPLAY INVISIBLE (-1800 3325);
FORCEADD Q_RES..1
(-1750 3275);
FORCEPROP 1 LAST MATERIAL CHIP
J 0
(-1550 3275);
DISPLAY 0.510638 (-1550 3275);
PAINT SKYBLUE (-1550 3275);
FORCEPROP 1 LAST VALUE 33.2
J 0
(-1650 3275);
DISPLAY 0.510638 (-1650 3275);
PAINT SKYBLUE (-1650 3275);
FORCEPROP 1 LAST TOLERANCE 1%
J 0
(-1625 3275);
DISPLAY 0.510638 (-1625 3275);
PAINT SKYBLUE (-1625 3275);
DISPLAY INVISIBLE (-1625 3275);
FORCEPROP 1 LAST PART_NUMBER CS03322FB03
J 0
(-1800 3375);
DISPLAY 0.510638 (-1800 3375);
PAINT WHITE (-1800 3375);
DISPLAY INVISIBLE (-1800 3375);
FORCEPROP 1 LAST PACK_TYPE 0402LF
J 0
(-1500 3125);
DISPLAY 0.510638 (-1500 3125);
PAINT SKYBLUE (-1500 3125);
DISPLAY INVISIBLE (-1500 3125);
FORCEPROP 1 LAST WATTAGE 1/16W
J 2
(-1775 3125);
DISPLAY 0.510638 (-1775 3125);
PAINT SKYBLUE (-1775 3125);
DISPLAY INVISIBLE (-1775 3125);
FORCEPROP 1 LAST PATH I301
J 0
(-1800 3425);
DISPLAY 0.978723 (-1800 3425);
PAINT WHITE (-1800 3425);
DISPLAY INVISIBLE (-1800 3425);
FORCEPROP 2 LAST CDS_LIB pure_quanta
J 0
(-1750 3275);
DISPLAY INVISIBLE (-1750 3275);
FORCEPROP 1 LAST LOCATION R442
J 0
(-1975 3275);
DISPLAY 0.702128 (-1975 3275);
PAINT YELLOW (-1975 3275);
FORCEPROP 1 LASTPIN (-1850 3275) $PN 1
J 0
(-1838 3287);
DISPLAY 0.808511 (-1838 3287);
PAINT WHITE (-1838 3287);
FORCEPROP 1 LASTPIN (-1650 3275) $PN 2
J 0
(-1688 3287);
DISPLAY 0.808511 (-1688 3287);
PAINT WHITE (-1688 3287);
FORCEPROP 2 LAST $SEC 1
J 0
(-1800 3475);
DISPLAY 0.680851 (-1800 3475);
PAINT MONO (-1800 3475);
DISPLAY INVISIBLE (-1800 3475);
FORCEPROP 0 LAST CDS_SEC 1
J 0
(-1800 3475);
DISPLAY 0.680851 (-1800 3475);
PAINT MONO (-1800 3475);
DISPLAY INVISIBLE (-1800 3475);
FORCEADD OFFPAGE..6
(-2975 3225);
FORCEPROP 2 LAST $XR1 35 
J 0
(-3344 3225);
DISPLAY 0.638298 (-3344 3225);
PAINT MONO (-3344 3225);
FORCEPROP 2 LAST $XR0 27 
J 0
(-3254 3225);
DISPLAY 0.638298 (-3254 3225);
PAINT MONO (-3254 3225);
FORCEPROP 2 LAST CDS_LIB standard
J 0
(-2975 3225);
DISPLAY INVISIBLE (-2975 3225);
FORCEPROP 1 LAST OFFPAGE TRUE
J 0
(-2650 3100);
DISPLAY 0.872340 (-2650 3100);
DISPLAY INVISIBLE (-2650 3100);
FORCEPROP 1 LAST COMMENT_BODY TRUE
J 0
(-2875 3150);
DISPLAY 0.872340 (-2875 3150);
PAINT GREEN (-2875 3150);
DISPLAY INVISIBLE (-2875 3150);
FORCEPROP 2 LAST PATH I303
J 0
(-3225 3275);
DISPLAY 0.680851 (-3225 3275);
DISPLAY INVISIBLE (-3225 3275);
FORCEADD Q_RES..1
(-1750 3075);
FORCEPROP 1 LAST VALUE 33.2
J 0
(-1650 3075);
DISPLAY 0.510638 (-1650 3075);
PAINT SKYBLUE (-1650 3075);
FORCEPROP 1 LAST MATERIAL CHIP
J 0
(-1550 3075);
DISPLAY 0.510638 (-1550 3075);
PAINT SKYBLUE (-1550 3075);
FORCEPROP 2 LAST CDS_LIB pure_quanta
J 0
(-1750 3075);
DISPLAY INVISIBLE (-1750 3075);
FORCEPROP 1 LAST PATH I306
J 0
(-1800 3225);
DISPLAY 0.978723 (-1800 3225);
PAINT WHITE (-1800 3225);
DISPLAY INVISIBLE (-1800 3225);
FORCEPROP 1 LAST WATTAGE 1/16W
J 2
(-1775 2925);
DISPLAY 0.510638 (-1775 2925);
PAINT SKYBLUE (-1775 2925);
DISPLAY INVISIBLE (-1775 2925);
FORCEPROP 1 LAST PACK_TYPE 0402LF
J 0
(-1500 2925);
DISPLAY 0.510638 (-1500 2925);
PAINT SKYBLUE (-1500 2925);
DISPLAY INVISIBLE (-1500 2925);
FORCEPROP 1 LAST PART_NUMBER CS03322FB03
J 0
(-1800 3175);
DISPLAY 0.510638 (-1800 3175);
PAINT WHITE (-1800 3175);
DISPLAY INVISIBLE (-1800 3175);
FORCEPROP 1 LAST TOLERANCE 1%
J 0
(-1625 3075);
DISPLAY 0.510638 (-1625 3075);
PAINT SKYBLUE (-1625 3075);
DISPLAY INVISIBLE (-1625 3075);
FORCEPROP 1 LAST LOCATION R444
J 0
(-1975 3075);
DISPLAY 0.702128 (-1975 3075);
PAINT YELLOW (-1975 3075);
FORCEPROP 1 LASTPIN (-1850 3075) $PN 1
J 0
(-1838 3087);
DISPLAY 0.808511 (-1838 3087);
PAINT WHITE (-1838 3087);
FORCEPROP 1 LASTPIN (-1650 3075) $PN 2
J 0
(-1688 3087);
DISPLAY 0.808511 (-1688 3087);
PAINT WHITE (-1688 3087);
FORCEPROP 0 LAST $SEC 1
J 0
(-1800 3175);
DISPLAY 0.680851 (-1800 3175);
PAINT MONO (-1800 3175);
DISPLAY INVISIBLE (-1800 3175);
FORCEPROP 0 LAST CDS_SEC 1
J 0
(-1800 3175);
DISPLAY 0.680851 (-1800 3175);
DISPLAY INVISIBLE (-1800 3175);
FORCEADD OFFPAGE..5
(-2975 3075);
FORCEPROP 2 LAST $XR0 35 
J 0
(-3229 3075);
DISPLAY 0.638298 (-3229 3075);
PAINT MONO (-3229 3075);
FORCEPROP 2 LAST CDS_LIB standard
J 0
(-2975 3075);
DISPLAY INVISIBLE (-2975 3075);
FORCEPROP 1 LAST OFFPAGE TRUE
J 0
(-2650 2950);
DISPLAY 0.872340 (-2650 2950);
PAINT GREEN (-2650 2950);
DISPLAY INVISIBLE (-2650 2950);
FORCEPROP 1 LAST COMMENT_BODY TRUE
J 0
(-2875 3000);
DISPLAY 0.872340 (-2875 3000);
PAINT PEACH (-2875 3000);
DISPLAY INVISIBLE (-2875 3000);
FORCEPROP 2 LAST PATH I307
J 0
(-3175 3125);
DISPLAY 0.680851 (-3175 3125);
DISPLAY INVISIBLE (-3175 3125);
FORCEADD OFFPAGE..5
(-2975 3175);
FORCEPROP 2 LAST $XR0 44 
J 0
(-3229 3175);
DISPLAY 0.638298 (-3229 3175);
PAINT MONO (-3229 3175);
FORCEPROP 2 LAST CDS_LIB standard
J 0
(-2975 3175);
DISPLAY INVISIBLE (-2975 3175);
FORCEPROP 1 LAST OFFPAGE TRUE
J 0
(-2650 3050);
DISPLAY 0.872340 (-2650 3050);
PAINT GREEN (-2650 3050);
DISPLAY INVISIBLE (-2650 3050);
FORCEPROP 1 LAST COMMENT_BODY TRUE
J 0
(-2875 3100);
DISPLAY 0.872340 (-2875 3100);
PAINT PEACH (-2875 3100);
DISPLAY INVISIBLE (-2875 3100);
FORCEPROP 2 LAST PATH I308
J 0
(-3175 3225);
DISPLAY 0.680851 (-3175 3225);
DISPLAY INVISIBLE (-3175 3225);
FORCEADD OFFPAGE..6
(-2975 3275);
FORCEPROP 2 LAST $XR1 35 
J 0
(-3344 3275);
DISPLAY 0.638298 (-3344 3275);
PAINT MONO (-3344 3275);
FORCEPROP 2 LAST $XR0 27 
J 0
(-3254 3275);
DISPLAY 0.638298 (-3254 3275);
PAINT MONO (-3254 3275);
FORCEPROP 2 LAST CDS_LIB standard
J 0
(-2975 3275);
DISPLAY INVISIBLE (-2975 3275);
FORCEPROP 1 LAST OFFPAGE TRUE
J 0
(-2650 3150);
DISPLAY 0.872340 (-2650 3150);
DISPLAY INVISIBLE (-2650 3150);
FORCEPROP 1 LAST COMMENT_BODY TRUE
J 0
(-2875 3200);
DISPLAY 0.872340 (-2875 3200);
PAINT GREEN (-2875 3200);
DISPLAY INVISIBLE (-2875 3200);
FORCEPROP 2 LAST PATH I309
J 0
(-2925 3350);
DISPLAY 0.680851 (-2925 3350);
DISPLAY INVISIBLE (-2925 3350);
FORCEADD Q_CAP..1
(-1550 -150);
FORCEPROP 1 LAST VOLTAGE 25V
J 0
(-1500 -150);
DISPLAY 0.510638 (-1500 -150);
PAINT SKYBLUE (-1500 -150);
FORCEPROP 1 LAST TOLERANCE 10%
J 0
(-1500 -200);
DISPLAY 0.510638 (-1500 -200);
PAINT SKYBLUE (-1500 -200);
FORCEPROP 1 LAST MATERIAL X6S
J 0
(-1500 -250);
DISPLAY 0.510638 (-1500 -250);
PAINT SKYBLUE (-1500 -250);
FORCEPROP 1 LAST PACK_TYPE C0402
J 0
(-1525 -300);
DISPLAY 0.510638 (-1525 -300);
PAINT SKYBLUE (-1525 -300);
FORCEPROP 1 LAST VALUE 1UF
J 0
(-1500 -100);
DISPLAY 0.510638 (-1500 -100);
PAINT SKYBLUE (-1500 -100);
FORCEPROP 1 LAST PATH I31
J 0
(-1500 0);
DISPLAY 0.978723 (-1500 0);
PAINT WHITE (-1500 0);
DISPLAY INVISIBLE (-1500 0);
FORCEPROP 1 LAST PART_NUMBER CH5104KEB02
J 0
(-1550 -375);
DISPLAY 0.510638 (-1550 -375);
PAINT WHITE (-1550 -375);
DISPLAY INVISIBLE (-1550 -375);
FORCEPROP 2 LAST CDS_LIB pure_quanta
J 0
(-1550 -150);
DISPLAY INVISIBLE (-1550 -150);
FORCEPROP 1 LAST LOCATION C32
J 0
(-1500 -50);
DISPLAY 0.702128 (-1500 -50);
PAINT YELLOW (-1500 -50);
FORCEPROP 1 LASTPIN (-1550 -50) $PN 1
J 0
(-1540 -70);
DISPLAY 0.808511 (-1540 -70);
PAINT WHITE (-1540 -70);
FORCEPROP 1 LASTPIN (-1550 -250) $PN 2
J 0
(-1540 -270);
DISPLAY 0.808511 (-1540 -270);
PAINT WHITE (-1540 -270);
FORCEPROP 0 LAST $SEC 1
J 0
(-1500 0);
DISPLAY 0.680851 (-1500 0);
PAINT MONO (-1500 0);
DISPLAY INVISIBLE (-1500 0);
FORCEPROP 0 LAST CDS_SEC 1
J 0
(-1500 0);
DISPLAY 0.680851 (-1500 0);
DISPLAY INVISIBLE (-1500 0);
FORCEADD Q_RES..1
(-1775 3975);
FORCEPROP 1 LAST VALUE 33.2
J 0
(-1675 3975);
DISPLAY 0.510638 (-1675 3975);
PAINT SKYBLUE (-1675 3975);
FORCEPROP 1 LAST MATERIAL CHIP
J 0
(-1925 3975);
DISPLAY 0.510638 (-1925 3975);
PAINT SKYBLUE (-1925 3975);
FORCEPROP 1 LAST TOLERANCE 1%
J 0
(-1650 3975);
DISPLAY 0.510638 (-1650 3975);
PAINT SKYBLUE (-1650 3975);
DISPLAY INVISIBLE (-1650 3975);
FORCEPROP 1 LAST PART_NUMBER CS03322FB03
J 0
(-1825 4075);
DISPLAY 0.510638 (-1825 4075);
PAINT WHITE (-1825 4075);
DISPLAY INVISIBLE (-1825 4075);
FORCEPROP 1 LAST WATTAGE 1/16W
J 2
(-1800 3825);
DISPLAY 0.510638 (-1800 3825);
PAINT SKYBLUE (-1800 3825);
DISPLAY INVISIBLE (-1800 3825);
FORCEPROP 2 LAST CDS_LIB pure_quanta
J 0
(-1775 3975);
DISPLAY INVISIBLE (-1775 3975);
FORCEPROP 1 LAST PATH I312
J 0
(-1825 4125);
DISPLAY 0.978723 (-1825 4125);
PAINT WHITE (-1825 4125);
DISPLAY INVISIBLE (-1825 4125);
FORCEPROP 1 LAST PACK_TYPE 0402LF
J 0
(-1525 3825);
DISPLAY 0.510638 (-1525 3825);
PAINT SKYBLUE (-1525 3825);
DISPLAY INVISIBLE (-1525 3825);
FORCEPROP 1 LAST LOCATION R460
J 0
(-2050 3975);
DISPLAY 0.702128 (-2050 3975);
PAINT YELLOW (-2050 3975);
FORCEPROP 1 LASTPIN (-1875 3975) $PN 1
J 0
(-1863 3987);
DISPLAY 0.808511 (-1863 3987);
PAINT WHITE (-1863 3987);
FORCEPROP 1 LASTPIN (-1675 3975) $PN 2
J 0
(-1713 3987);
DISPLAY 0.808511 (-1713 3987);
PAINT WHITE (-1713 3987);
FORCEPROP 0 LAST $SEC 1
J 0
(-2050 4025);
DISPLAY 0.680851 (-2050 4025);
PAINT MONO (-2050 4025);
DISPLAY INVISIBLE (-2050 4025);
FORCEPROP 0 LAST CDS_SEC 1
J 0
(-2050 4025);
DISPLAY 0.680851 (-2050 4025);
DISPLAY INVISIBLE (-2050 4025);
FORCEADD OFFPAGE..6
(-2975 3975);
FORCEPROP 2 LAST $XR0 13 
J 0
(-3254 3975);
DISPLAY 0.638298 (-3254 3975);
PAINT MONO (-3254 3975);
FORCEPROP 2 LAST $XR1 46 
J 0
(-3344 3975);
DISPLAY 0.638298 (-3344 3975);
PAINT MONO (-3344 3975);
FORCEPROP 1 LAST COMMENT_BODY TRUE
J 0
(-2875 3900);
DISPLAY 0.872340 (-2875 3900);
PAINT GREEN (-2875 3900);
DISPLAY INVISIBLE (-2875 3900);
FORCEPROP 1 LAST OFFPAGE TRUE
J 0
(-2650 3850);
DISPLAY 0.872340 (-2650 3850);
DISPLAY INVISIBLE (-2650 3850);
FORCEPROP 2 LAST CDS_LIB standard
J 0
(-2975 3975);
DISPLAY INVISIBLE (-2975 3975);
FORCEPROP 2 LAST PATH I313
J 0
(-2925 4050);
DISPLAY 0.680851 (-2925 4050);
DISPLAY INVISIBLE (-2925 4050);
FORCEADD Q_RES..1
(3250 3925);
FORCEPROP 1 LAST MATERIAL CHIP
J 0
(3450 3925);
DISPLAY 0.510638 (3450 3925);
PAINT SKYBLUE (3450 3925);
FORCEPROP 1 LAST VALUE 33.2
J 2
(3425 3925);
DISPLAY 0.510638 (3425 3925);
PAINT SKYBLUE (3425 3925);
FORCEPROP 1 LAST TOLERANCE 1%
J 0
(3175 4025);
DISPLAY 0.510638 (3175 4025);
PAINT SKYBLUE (3175 4025);
DISPLAY INVISIBLE (3175 4025);
FORCEPROP 1 LAST PART_NUMBER CS03322FB03
J 0
(3150 4000);
DISPLAY 0.510638 (3150 4000);
PAINT WHITE (3150 4000);
DISPLAY INVISIBLE (3150 4000);
FORCEPROP 1 LAST PACK_TYPE 0402LF
J 0
(3225 3975);
DISPLAY 0.510638 (3225 3975);
PAINT SKYBLUE (3225 3975);
DISPLAY INVISIBLE (3225 3975);
FORCEPROP 1 LAST WATTAGE 1/16W
J 2
(3600 4025);
DISPLAY 0.510638 (3600 4025);
PAINT SKYBLUE (3600 4025);
DISPLAY INVISIBLE (3600 4025);
FORCEPROP 1 LAST PATH I319
J 0
(3200 4075);
DISPLAY 0.978723 (3200 4075);
PAINT WHITE (3200 4075);
DISPLAY INVISIBLE (3200 4075);
FORCEPROP 2 LAST CDS_LIB pure_quanta
J 0
(3250 3925);
DISPLAY INVISIBLE (3250 3925);
FORCEPROP 1 LAST LOCATION R469
J 0
(3025 3925);
DISPLAY 0.702128 (3025 3925);
PAINT YELLOW (3025 3925);
FORCEPROP 0 LAST $SEC 1
J 0
(3025 3975);
DISPLAY 0.680851 (3025 3975);
PAINT MONO (3025 3975);
DISPLAY INVISIBLE (3025 3975);
FORCEPROP 0 LAST CDS_SEC 1
J 0
(3025 3975);
DISPLAY 1.021277 (3025 3975);
DISPLAY INVISIBLE (3025 3975);
FORCEPROP 1 LASTPIN (3150 3925) $PN 1
J 0
(3162 3937);
DISPLAY 0.808511 (3162 3937);
PAINT WHITE (3162 3937);
DISPLAY INVISIBLE (3162 3937);
FORCEPROP 1 LASTPIN (3350 3925) $PN 2
J 0
(3312 3937);
DISPLAY 0.808511 (3312 3937);
PAINT WHITE (3312 3937);
DISPLAY INVISIBLE (3312 3937);
FORCEADD Q_CAP..1
(-1350 -150);
FORCEPROP 1 LAST PACK_TYPE 0402
J 0
(-1300 -300);
DISPLAY 0.510638 (-1300 -300);
PAINT SKYBLUE (-1300 -300);
FORCEPROP 1 LAST VOLTAGE 25V
J 0
(-1300 -150);
DISPLAY 0.510638 (-1300 -150);
PAINT SKYBLUE (-1300 -150);
FORCEPROP 1 LAST VALUE 0.1UF
J 0
(-1300 -100);
DISPLAY 0.510638 (-1300 -100);
PAINT SKYBLUE (-1300 -100);
FORCEPROP 1 LAST TOLERANCE 10%
J 0
(-1300 -200);
DISPLAY 0.510638 (-1300 -200);
PAINT SKYBLUE (-1300 -200);
FORCEPROP 1 LAST MATERIAL X7R
J 0
(-1300 -250);
DISPLAY 0.510638 (-1300 -250);
PAINT SKYBLUE (-1300 -250);
FORCEPROP 1 LAST PATH I32
J 0
(-1300 0);
DISPLAY 0.978723 (-1300 0);
PAINT WHITE (-1300 0);
DISPLAY INVISIBLE (-1300 0);
FORCEPROP 1 LAST PART_NUMBER CH4104K1B00
J 0
(-1300 -300);
DISPLAY 0.510638 (-1300 -300);
PAINT WHITE (-1300 -300);
DISPLAY INVISIBLE (-1300 -300);
FORCEPROP 2 LAST CDS_LIB pure_quanta
J 0
(-1350 -150);
DISPLAY INVISIBLE (-1350 -150);
FORCEPROP 1 LAST LOCATION C33
J 0
(-1300 -50);
DISPLAY 0.702128 (-1300 -50);
PAINT YELLOW (-1300 -50);
FORCEPROP 1 LASTPIN (-1350 -50) $PN 1
J 0
(-1340 -70);
DISPLAY 0.808511 (-1340 -70);
PAINT WHITE (-1340 -70);
FORCEPROP 1 LASTPIN (-1350 -250) $PN 2
J 0
(-1340 -270);
DISPLAY 0.808511 (-1340 -270);
PAINT WHITE (-1340 -270);
FORCEPROP 0 LAST $SEC 1
J 0
(-1300 0);
DISPLAY 0.680851 (-1300 0);
PAINT MONO (-1300 0);
DISPLAY INVISIBLE (-1300 0);
FORCEPROP 0 LAST CDS_SEC 1
J 0
(-1300 0);
DISPLAY 0.680851 (-1300 0);
DISPLAY INVISIBLE (-1300 0);
FORCEADD OFFPAGE..3
(4475 3925);
FORCEPROP 2 LAST $XR0 46 
J 0
(4689 3925);
DISPLAY 0.638298 (4689 3925);
PAINT MONO (4689 3925);
FORCEPROP 2 LAST PATH I320
J 0
(4700 3975);
DISPLAY 0.680851 (4700 3975);
DISPLAY INVISIBLE (4700 3975);
FORCEPROP 1 LAST COMMENT_BODY TRUE
J 0
(4425 3825);
DISPLAY 0.872340 (4425 3825);
PAINT PEACH (4425 3825);
DISPLAY INVISIBLE (4425 3825);
FORCEPROP 1 LAST OFFPAGE TRUE
J 0
(4800 3800);
DISPLAY 0.872340 (4800 3800);
PAINT GREEN (4800 3800);
DISPLAY INVISIBLE (4800 3800);
FORCEPROP 2 LAST CDS_LIB standard
J 0
(4475 3925);
DISPLAY INVISIBLE (4475 3925);
FORCEADD Q_RES..1
(-325 -525);
FORCEPROP 1 LAST MATERIAL CHIP
J 0
(-150 -425);
DISPLAY 0.510638 (-150 -425);
PAINT SKYBLUE (-150 -425);
FORCEPROP 1 LAST TOLERANCE 1%
J 0
(175 -425);
DISPLAY 0.510638 (175 -425);
PAINT SKYBLUE (175 -425);
FORCEPROP 1 LAST VALUE 330
J 2
(-100 -525);
DISPLAY 0.510638 (-100 -525);
PAINT SKYBLUE (-100 -525);
FORCEPROP 1 LAST WATTAGE 1/16W
J 2
(150 -425);
DISPLAY 0.510638 (150 -425);
PAINT SKYBLUE (150 -425);
FORCEPROP 1 LAST PACK_TYPE 0402LF
J 0
(-375 -425);
DISPLAY 0.510638 (-375 -425);
PAINT SKYBLUE (-375 -425);
FORCEPROP 1 LAST PART_NUMBER CS13302FB00
J 0
(-375 -375);
DISPLAY 0.510638 (-375 -375);
PAINT WHITE (-375 -375);
FORCEPROP 1 LAST PATH I33
J 0
(-375 -375);
DISPLAY 0.978723 (-375 -375);
PAINT WHITE (-375 -375);
DISPLAY INVISIBLE (-375 -375);
FORCEPROP 2 LAST CDS_LIB pure_quanta
J 0
(-325 -525);
DISPLAY INVISIBLE (-325 -525);
FORCEPROP 1 LAST LOCATION R167
J 0
(-550 -525);
DISPLAY 0.702128 (-550 -525);
PAINT YELLOW (-550 -525);
FORCEPROP 1 LASTPIN (-425 -525) $PN 1
J 0
(-413 -513);
DISPLAY 0.808511 (-413 -513);
PAINT WHITE (-413 -513);
FORCEPROP 1 LASTPIN (-225 -525) $PN 2
J 0
(-263 -513);
DISPLAY 0.808511 (-263 -513);
PAINT WHITE (-263 -513);
FORCEPROP 2 LAST $SEC 1
J 0
(-375 -325);
DISPLAY 0.680851 (-375 -325);
PAINT MONO (-375 -325);
DISPLAY INVISIBLE (-375 -325);
FORCEPROP 0 LAST CDS_SEC 1
J 0
(-375 -325);
DISPLAY 0.680851 (-375 -325);
PAINT MONO (-375 -325);
DISPLAY INVISIBLE (-375 -325);
FORCEADD OFFPAGE..4
(4925 3125);
FORCEPROP 2 LAST $XR1 36 
J 0
(5201 3125);
DISPLAY 0.638298 (5201 3125);
PAINT MONO (5201 3125);
FORCEPROP 2 LAST $XR0 13 
J 0
(5111 3125);
DISPLAY 0.638298 (5111 3125);
PAINT MONO (5111 3125);
FORCEPROP 2 LAST PATH I333
J 0
(5225 3175);
DISPLAY 0.680851 (5225 3175);
DISPLAY INVISIBLE (5225 3175);
FORCEPROP 1 LAST COMMENT_BODY TRUE
J 0
(4900 3025);
DISPLAY 0.872340 (4900 3025);
PAINT GREEN (4900 3025);
DISPLAY INVISIBLE (4900 3025);
FORCEPROP 1 LAST OFFPAGE TRUE
J 0
(5250 3000);
DISPLAY 0.872340 (5250 3000);
DISPLAY INVISIBLE (5250 3000);
FORCEPROP 2 LAST CDS_LIB standard
J 0
(4925 3125);
DISPLAY INVISIBLE (4925 3125);
FORCEADD Q_RES..1
(3650 3175);
FORCEPROP 1 LAST MATERIAL CHIP
J 1
(3900 3175);
DISPLAY 0.510638 (3900 3175);
PAINT SKYBLUE (3900 3175);
FORCEPROP 1 LAST VALUE 33.2
J 1
(3800 3175);
DISPLAY 0.510638 (3800 3175);
PAINT SKYBLUE (3800 3175);
FORCEPROP 1 LAST TOLERANCE 1%
J 0
(3875 3125);
DISPLAY 0.510638 (3875 3125);
PAINT SKYBLUE (3875 3125);
DISPLAY INVISIBLE (3875 3125);
FORCEPROP 1 LAST PART_NUMBER CS03322FB03
J 0
(3775 3225);
DISPLAY 0.510638 (3775 3225);
PAINT WHITE (3775 3225);
DISPLAY INVISIBLE (3775 3225);
FORCEPROP 1 LAST PACK_TYPE 0402LF
J 0
(3700 3125);
DISPLAY 0.510638 (3700 3125);
PAINT SKYBLUE (3700 3125);
DISPLAY INVISIBLE (3700 3125);
FORCEPROP 1 LAST WATTAGE 1/16W
J 2
(4050 3125);
DISPLAY 0.510638 (4050 3125);
PAINT SKYBLUE (4050 3125);
DISPLAY INVISIBLE (4050 3125);
FORCEPROP 1 LAST PATH I335
J 0
(3600 3325);
DISPLAY 0.978723 (3600 3325);
PAINT WHITE (3600 3325);
DISPLAY INVISIBLE (3600 3325);
FORCEPROP 2 LAST CDS_LIB pure_quanta
J 0
(3650 3175);
DISPLAY INVISIBLE (3650 3175);
FORCEPROP 2 LAST SEC_TYPE 0402LF
J 0
(3600 3375);
DISPLAY 0.680851 (3600 3375);
DISPLAY INVISIBLE (3600 3375);
FORCEPROP 1 LAST LOCATION R494
J 2
(3550 3175);
DISPLAY 0.702128 (3550 3175);
PAINT YELLOW (3550 3175);
FORCEPROP 1 LASTPIN (3550 3175) $PN 1
J 0
(3562 3187);
DISPLAY 0.808511 (3562 3187);
PAINT WHITE (3562 3187);
FORCEPROP 1 LASTPIN (3750 3175) $PN 2
J 0
(3715 3185);
DISPLAY 0.808511 (3715 3185);
PAINT WHITE (3715 3185);
FORCEPROP 2 LAST SEC 1
J 0
(3600 3375);
DISPLAY 0.680851 (3600 3375);
PAINT MONO (3600 3375);
DISPLAY INVISIBLE (3600 3375);
FORCEADD OFFPAGE..2
(4925 3175);
FORCEPROP 2 LAST $XR1 35 
J 0
(5114 3175);
DISPLAY 0.638298 (5114 3175);
PAINT MONO (5114 3175);
FORCEPROP 2 LAST $XR0 22 
J 0
(5114 3175);
DISPLAY 0.638298 (5114 3175);
PAINT MONO (5114 3175);
FORCEPROP 2 LAST PATH I336
J 0
(5225 3225);
DISPLAY 0.680851 (5225 3225);
DISPLAY INVISIBLE (5225 3225);
FORCEPROP 1 LAST COMMENT_BODY TRUE
J 0
(4880 3080);
DISPLAY 0.872340 (4880 3080);
PAINT PEACH (4880 3080);
DISPLAY INVISIBLE (4880 3080);
FORCEPROP 1 LAST OFFPAGE TRUE
J 0
(5250 3050);
DISPLAY 0.872340 (5250 3050);
PAINT GREEN (5250 3050);
DISPLAY INVISIBLE (5250 3050);
FORCEPROP 2 LAST CDS_LIB standard
J 0
(4925 3175);
DISPLAY INVISIBLE (4925 3175);
FORCEADD Q_RES..1
(3650 3125);
FORCEPROP 1 LAST MATERIAL CHIP
J 0
(3850 3125);
DISPLAY 0.510638 (3850 3125);
PAINT SKYBLUE (3850 3125);
FORCEPROP 1 LAST VALUE 0
J 2
(3800 3125);
DISPLAY 0.510638 (3800 3125);
PAINT SKYBLUE (3800 3125);
FORCEPROP 1 LAST PART_NUMBER CS00002JB13
J 0
(3550 3200);
DISPLAY 0.510638 (3550 3200);
PAINT WHITE (3550 3200);
DISPLAY INVISIBLE (3550 3200);
FORCEPROP 1 LAST PACK_TYPE 0402LF
J 0
(3625 3175);
DISPLAY 0.510638 (3625 3175);
PAINT SKYBLUE (3625 3175);
DISPLAY INVISIBLE (3625 3175);
FORCEPROP 1 LAST WATTAGE 1/16W
J 2
(4000 3225);
DISPLAY 0.510638 (4000 3225);
PAINT SKYBLUE (4000 3225);
DISPLAY INVISIBLE (4000 3225);
FORCEPROP 1 LAST PATH I337
J 0
(3600 3275);
DISPLAY 0.978723 (3600 3275);
PAINT WHITE (3600 3275);
DISPLAY INVISIBLE (3600 3275);
FORCEPROP 1 LAST TOLERANCE 5%
J 0
(3575 3225);
DISPLAY 0.510638 (3575 3225);
PAINT SKYBLUE (3575 3225);
DISPLAY INVISIBLE (3575 3225);
FORCEPROP 2 LAST CDS_LIB pure_quanta
J 0
(3650 3125);
DISPLAY INVISIBLE (3650 3125);
FORCEPROP 1 LAST LOCATION R637
J 0
(3450 3125);
DISPLAY 0.702128 (3450 3125);
PAINT YELLOW (3450 3125);
FORCEPROP 0 LAST $SEC 1
J 0
(3500 3175);
DISPLAY 0.680851 (3500 3175);
PAINT MONO (3500 3175);
DISPLAY INVISIBLE (3500 3175);
FORCEPROP 0 LAST CDS_SEC 1
J 0
(3500 3175);
DISPLAY 1.021277 (3500 3175);
DISPLAY INVISIBLE (3500 3175);
FORCEPROP 1 LASTPIN (3550 3125) $PN 1
J 0
(3562 3137);
DISPLAY 0.808511 (3562 3137);
PAINT WHITE (3562 3137);
DISPLAY INVISIBLE (3562 3137);
FORCEPROP 1 LASTPIN (3750 3125) $PN 2
J 0
(3712 3137);
DISPLAY 0.808511 (3712 3137);
PAINT WHITE (3712 3137);
DISPLAY INVISIBLE (3712 3137);
FORCEADD OFFPAGE..2
(4275 -900);
FORCEPROP 2 LAST $XR1 13 
J 0
(4554 -900);
DISPLAY 0.638298 (4554 -900);
PAINT MONO (4554 -900);
FORCEPROP 2 LAST $XR0 36 
J 0
(4464 -900);
DISPLAY 0.638298 (4464 -900);
PAINT MONO (4464 -900);
FORCEPROP 2 LAST PATH I338
J 0
(4575 -850);
DISPLAY 0.680851 (4575 -850);
DISPLAY INVISIBLE (4575 -850);
FORCEPROP 1 LAST COMMENT_BODY TRUE
J 0
(4230 -995);
DISPLAY 0.872340 (4230 -995);
PAINT PEACH (4230 -995);
DISPLAY INVISIBLE (4230 -995);
FORCEPROP 1 LAST OFFPAGE TRUE
J 0
(4600 -1025);
DISPLAY 0.872340 (4600 -1025);
PAINT GREEN (4600 -1025);
DISPLAY INVISIBLE (4600 -1025);
FORCEPROP 2 LAST CDS_LIB standard
J 0
(4275 -900);
DISPLAY INVISIBLE (4275 -900);
FORCEADD Q_RES..1
(2800 -900);
FORCEPROP 1 LAST MATERIAL CHIP
J 0
(3175 -900);
DISPLAY 0.510638 (3175 -900);
PAINT SKYBLUE (3175 -900);
FORCEPROP 1 LAST VALUE 4.7K
J 2
(3075 -900);
DISPLAY 0.510638 (3075 -900);
PAINT SKYBLUE (3075 -900);
FORCEPROP 1 LAST PART_NUMBER CS24702FB06
J 0
(2750 -800);
DISPLAY 0.510638 (2750 -800);
PAINT WHITE (2750 -800);
DISPLAY INVISIBLE (2750 -800);
FORCEPROP 1 LAST PACK_TYPE 0402LF
J 0
(3050 -1050);
DISPLAY 0.510638 (3050 -1050);
PAINT SKYBLUE (3050 -1050);
DISPLAY INVISIBLE (3050 -1050);
FORCEPROP 1 LAST WATTAGE 1/16W
J 2
(2775 -1050);
DISPLAY 0.510638 (2775 -1050);
PAINT SKYBLUE (2775 -1050);
DISPLAY INVISIBLE (2775 -1050);
FORCEPROP 1 LAST PATH I339
J 0
(2750 -750);
DISPLAY 0.978723 (2750 -750);
PAINT WHITE (2750 -750);
DISPLAY INVISIBLE (2750 -750);
FORCEPROP 1 LAST TOLERANCE 1%
J 0
(2800 -1000);
DISPLAY 0.510638 (2800 -1000);
PAINT SKYBLUE (2800 -1000);
DISPLAY INVISIBLE (2800 -1000);
FORCEPROP 2 LAST SEC_TYPE 0402LF
J 0
(2750 -700);
DISPLAY 0.680851 (2750 -700);
DISPLAY INVISIBLE (2750 -700);
FORCEPROP 2 LAST CDS_LIB pure_quanta
J 0
(2800 -900);
DISPLAY INVISIBLE (2800 -900);
FORCEPROP 1 LAST LOCATION R452
J 2
(2650 -900);
DISPLAY 0.702128 (2650 -900);
PAINT YELLOW (2650 -900);
FORCEPROP 1 LASTPIN (2700 -900) $PN 1
J 0
(2712 -888);
DISPLAY 0.808511 (2712 -888);
PAINT WHITE (2712 -888);
FORCEPROP 1 LASTPIN (2900 -900) $PN 2
J 0
(2862 -888);
DISPLAY 0.808511 (2862 -888);
PAINT WHITE (2862 -888);
FORCEPROP 2 LAST SEC 1
J 0
(2750 -700);
DISPLAY 0.680851 (2750 -700);
PAINT MONO (2750 -700);
DISPLAY INVISIBLE (2750 -700);
FORCEADD UNIVERSAL_POWER..1
(-575 -375);
FORCEPROP 3 LASTPIN (-575 -425) SIG_NAME P3V3_AUX\g
J 0
(-565 -415);
DISPLAY 0.659574 (-565 -415);
PAINT MONO (-565 -415);
DISPLAY INVISIBLE (-565 -415);
FORCEPROP 1 LAST HDL_POWER P3V3_AUX
J 1
(-575 -325);
DISPLAY 0.702128 (-575 -325);
PAINT GREEN (-575 -325);
FORCEPROP 1 LAST PATH I34
J 0
(-525 -350);
DISPLAY 0.872340 (-525 -350);
PAINT AQUA (-525 -350);
DISPLAY INVISIBLE (-525 -350);
FORCEPROP 2 LAST CDS_LIB logical_power
J 0
(-575 -375);
DISPLAY INVISIBLE (-575 -375);
FORCEADD Q_RES..1
R 2
(-2275 1025);
FORCEPROP 1 LAST MATERIAL CHIP
J 2
(-1850 1025);
DISPLAY 0.510638 (-1850 1025);
PAINT SKYBLUE (-1850 1025);
FORCEPROP 1 LAST VALUE 100K
J 0
(-2150 1025);
DISPLAY 0.510638 (-2150 1025);
PAINT SKYBLUE (-2150 1025);
FORCEPROP 2 LAST CDS_LIB pure_quanta
J 2
(-2275 1119);
DISPLAY INVISIBLE (-2275 1119);
FORCEPROP 2 LAST SEC_TYPE 0402LF
J 0
(-2225 1225);
DISPLAY 0.680851 (-2225 1225);
DISPLAY INVISIBLE (-2225 1225);
FORCEPROP 1 LAST PATH I340
J 2
(-2225 1175);
DISPLAY 0.978723 (-2225 1175);
PAINT WHITE (-2225 1175);
DISPLAY INVISIBLE (-2225 1175);
FORCEPROP 1 LAST TOLERANCE 1%
J 2
(-2275 950);
DISPLAY 0.510638 (-2275 950);
PAINT SKYBLUE (-2275 950);
DISPLAY INVISIBLE (-2275 950);
FORCEPROP 1 LAST PART_NUMBER CS41002FB09
J 2
(-2325 975);
DISPLAY 0.510638 (-2325 975);
PAINT WHITE (-2325 975);
DISPLAY INVISIBLE (-2325 975);
FORCEPROP 1 LAST WATTAGE 1/16W
J 0
(-2500 950);
DISPLAY 0.510638 (-2500 950);
PAINT SKYBLUE (-2500 950);
DISPLAY INVISIBLE (-2500 950);
FORCEPROP 1 LAST PACK_TYPE 0402LF
J 2
(-2075 950);
DISPLAY 0.510638 (-2075 950);
PAINT SKYBLUE (-2075 950);
DISPLAY INVISIBLE (-2075 950);
FORCEPROP 1 LAST LOCATION R273
J 2
(-2400 1025);
DISPLAY 0.702128 (-2400 1025);
PAINT YELLOW (-2400 1025);
FORCEPROP 1 LASTPIN (-2175 1025) $PN 1
J 0
(-2210 1035);
DISPLAY 0.808511 (-2210 1035);
PAINT WHITE (-2210 1035);
FORCEPROP 1 LASTPIN (-2375 1025) $PN 2
J 0
(-2360 1035);
DISPLAY 0.808511 (-2360 1035);
PAINT WHITE (-2360 1035);
FORCEPROP 0 LAST SEC 1
J 0
(-2175 1100);
DISPLAY 0.680851 (-2175 1100);
PAINT MONO (-2175 1100);
DISPLAY INVISIBLE (-2175 1100);
FORCEADD UNIVERSAL_GND..1
(-2400 925);
FORCEPROP 3 LASTPIN (-2400 975) SIG_NAME GND\g
J 0
(-2390 985);
DISPLAY 0.659574 (-2390 985);
PAINT MONO (-2390 985);
DISPLAY INVISIBLE (-2390 985);
FORCEPROP 2 LAST CDS_LIB logical_power
J 0
(-2400 925);
DISPLAY INVISIBLE (-2400 925);
FORCEPROP 1 LAST HDL_POWER GND
J 1
(-2375 850);
DISPLAY 0.702128 (-2375 850);
PAINT GREEN (-2375 850);
DISPLAY INVISIBLE (-2375 850);
FORCEPROP 1 LAST PATH I341
J 0
(-2325 925);
DISPLAY 0.872340 (-2325 925);
PAINT AQUA (-2325 925);
DISPLAY INVISIBLE (-2325 925);
FORCEADD Q_RES..1
(-1825 3675);
FORCEPROP 1 LAST MATERIAL CHIP
J 0
(-1975 3675);
DISPLAY 0.510638 (-1975 3675);
PAINT SKYBLUE (-1975 3675);
FORCEPROP 1 LAST VALUE 33.2
J 0
(-1750 3675);
DISPLAY 0.510638 (-1750 3675);
PAINT SKYBLUE (-1750 3675);
FORCEPROP 2 LAST CDS_LIB pure_quanta
J 0
(-1825 3675);
DISPLAY INVISIBLE (-1825 3675);
FORCEPROP 1 LAST PATH I344
J 0
(-1875 3825);
DISPLAY 0.978723 (-1875 3825);
PAINT WHITE (-1875 3825);
DISPLAY INVISIBLE (-1875 3825);
FORCEPROP 1 LAST WATTAGE 1/16W
J 2
(-1850 3525);
DISPLAY 0.510638 (-1850 3525);
PAINT SKYBLUE (-1850 3525);
DISPLAY INVISIBLE (-1850 3525);
FORCEPROP 1 LAST PART_NUMBER CS03322FB03
J 0
(-1875 3775);
DISPLAY 0.510638 (-1875 3775);
PAINT WHITE (-1875 3775);
DISPLAY INVISIBLE (-1875 3775);
FORCEPROP 1 LAST TOLERANCE 1%
J 0
(-1700 3675);
DISPLAY 0.510638 (-1700 3675);
PAINT SKYBLUE (-1700 3675);
DISPLAY INVISIBLE (-1700 3675);
FORCEPROP 1 LAST PACK_TYPE 0402LF
J 0
(-1575 3525);
DISPLAY 0.510638 (-1575 3525);
PAINT SKYBLUE (-1575 3525);
DISPLAY INVISIBLE (-1575 3525);
FORCEPROP 1 LAST LOCATION R643
J 0
(-2100 3675);
DISPLAY 0.702128 (-2100 3675);
PAINT YELLOW (-2100 3675);
FORCEPROP 1 LASTPIN (-1925 3675) $PN 1
J 0
(-1913 3687);
DISPLAY 0.808511 (-1913 3687);
PAINT WHITE (-1913 3687);
FORCEPROP 1 LASTPIN (-1725 3675) $PN 2
J 0
(-1763 3687);
DISPLAY 0.808511 (-1763 3687);
PAINT WHITE (-1763 3687);
FORCEPROP 0 LAST $SEC 1
J 0
(-2100 3725);
DISPLAY 0.680851 (-2100 3725);
PAINT MONO (-2100 3725);
DISPLAY INVISIBLE (-2100 3725);
FORCEPROP 0 LAST CDS_SEC 1
J 0
(-2100 3725);
DISPLAY 0.680851 (-2100 3725);
DISPLAY INVISIBLE (-2100 3725);
FORCEADD OFFPAGE..1
(-2975 3675);
FORCEPROP 2 LAST $XR1 42 
J 0
(-3316 3675);
DISPLAY 0.638298 (-3316 3675);
PAINT MONO (-3316 3675);
FORCEPROP 2 LAST $XR0 36 
J 0
(-3226 3675);
DISPLAY 0.638298 (-3226 3675);
PAINT MONO (-3226 3675);
FORCEPROP 2 LAST $XR2 28 
J 0
(-3406 3675);
DISPLAY 0.638298 (-3406 3675);
PAINT MONO (-3406 3675);
FORCEPROP 2 LAST PATH I345
J 0
(-3250 3725);
DISPLAY 0.680851 (-3250 3725);
DISPLAY INVISIBLE (-3250 3725);
FORCEPROP 1 LAST COMMENT_BODY TRUE
J 0
(-2850 3575);
DISPLAY 0.872340 (-2850 3575);
PAINT GREEN (-2850 3575);
DISPLAY INVISIBLE (-2850 3575);
FORCEPROP 1 LAST OFFPAGE TRUE
J 0
(-2650 3550);
DISPLAY 0.872340 (-2650 3550);
DISPLAY INVISIBLE (-2650 3550);
FORCEPROP 2 LAST CDS_LIB standard
J 0
(-2975 3675);
DISPLAY INVISIBLE (-2975 3675);
FORCEADD Q_RES..1
(3800 2775);
FORCEPROP 1 LAST VALUE 33.2
J 1
(3950 2775);
DISPLAY 0.510638 (3950 2775);
PAINT SKYBLUE (3950 2775);
FORCEPROP 1 LAST MATERIAL CHIP
J 1
(4050 2775);
DISPLAY 0.510638 (4050 2775);
PAINT SKYBLUE (4050 2775);
FORCEPROP 1 LAST TOLERANCE 1%
J 0
(3925 2775);
DISPLAY 0.510638 (3925 2775);
PAINT SKYBLUE (3925 2775);
DISPLAY INVISIBLE (3925 2775);
FORCEPROP 1 LAST PART_NUMBER CS03322FB03
J 0
(3750 2875);
DISPLAY 0.510638 (3750 2875);
PAINT WHITE (3750 2875);
DISPLAY INVISIBLE (3750 2875);
FORCEPROP 1 LAST PACK_TYPE 0402LF
J 0
(4050 2625);
DISPLAY 0.510638 (4050 2625);
PAINT SKYBLUE (4050 2625);
DISPLAY INVISIBLE (4050 2625);
FORCEPROP 1 LAST WATTAGE 1/16W
J 2
(3775 2625);
DISPLAY 0.510638 (3775 2625);
PAINT SKYBLUE (3775 2625);
DISPLAY INVISIBLE (3775 2625);
FORCEPROP 1 LAST PATH I349
J 0
(3750 2925);
DISPLAY 0.978723 (3750 2925);
PAINT WHITE (3750 2925);
DISPLAY INVISIBLE (3750 2925);
FORCEPROP 2 LAST CDS_LIB pure_quanta
J 0
(3800 2775);
DISPLAY INVISIBLE (3800 2775);
FORCEPROP 2 LAST SEC_TYPE 0402LF
J 0
(3750 2975);
DISPLAY 0.680851 (3750 2975);
DISPLAY INVISIBLE (3750 2975);
FORCEPROP 1 LAST LOCATION R407
J 2
(3700 2775);
DISPLAY 0.702128 (3700 2775);
PAINT YELLOW (3700 2775);
FORCEPROP 1 LASTPIN (3700 2775) $PN 1
J 0
(3712 2787);
DISPLAY 0.808511 (3712 2787);
PAINT WHITE (3712 2787);
FORCEPROP 1 LASTPIN (3900 2775) $PN 2
J 0
(3862 2787);
DISPLAY 0.808511 (3862 2787);
PAINT WHITE (3862 2787);
FORCEPROP 0 LAST SEC 1
J 0
(3550 2825);
DISPLAY 0.680851 (3550 2825);
PAINT MONO (3550 2825);
DISPLAY INVISIBLE (3550 2825);
FORCEADD UNIVERSAL_POWER..1
(-1225 250);
FORCEPROP 3 LASTPIN (-1225 200) SIG_NAME P3V3_P2V5_P1V8_RVDD\g
J 0
(-1215 210);
DISPLAY 0.659574 (-1215 210);
PAINT MONO (-1215 210);
DISPLAY INVISIBLE (-1215 210);
FORCEPROP 1 LAST HDL_POWER P3V3_P2V5_P1V8_RVDD
J 1
(-1400 300);
DISPLAY 0.702128 (-1400 300);
PAINT GREEN (-1400 300);
FORCEPROP 1 LAST PATH I35
J 0
(-1175 275);
DISPLAY 0.872340 (-1175 275);
PAINT AQUA (-1175 275);
DISPLAY INVISIBLE (-1175 275);
FORCEPROP 2 LAST CDS_LIB logical_power
J 0
(-1225 250);
DISPLAY INVISIBLE (-1225 250);
FORCEADD Q_RES..1
R 2
(-2175 2875);
FORCEPROP 1 LAST VALUE 0
J 0
(-2100 2875);
DISPLAY 0.510638 (-2100 2875);
PAINT SKYBLUE (-2100 2875);
FORCEPROP 1 LAST MATERIAL CHIP
J 2
(-1925 2875);
DISPLAY 0.510638 (-1925 2875);
PAINT SKYBLUE (-1925 2875);
FORCEPROP 1 LAST TOLERANCE 5%
J 2
(-2025 2850);
DISPLAY 0.510638 (-2025 2850);
PAINT SKYBLUE (-2025 2850);
DISPLAY INVISIBLE (-2025 2850);
FORCEPROP 1 LAST WATTAGE 1/16W
J 0
(-1875 2850);
DISPLAY 0.510638 (-1875 2850);
PAINT SKYBLUE (-1875 2850);
DISPLAY INVISIBLE (-1875 2850);
FORCEPROP 1 LAST PACK_TYPE 0402LF
J 2
(-1575 2850);
DISPLAY 0.510638 (-1575 2850);
PAINT SKYBLUE (-1575 2850);
DISPLAY INVISIBLE (-1575 2850);
FORCEPROP 1 LAST PART_NUMBER CS00002JB13
J 2
(-1925 2900);
DISPLAY 0.510638 (-1925 2900);
PAINT WHITE (-1925 2900);
DISPLAY INVISIBLE (-1925 2900);
FORCEPROP 1 LAST PATH I350
J 2
(-2125 3025);
DISPLAY 0.978723 (-2125 3025);
PAINT WHITE (-2125 3025);
DISPLAY INVISIBLE (-2125 3025);
FORCEPROP 2 LAST CDS_LIB pure_quanta
J 0
(-2175 2875);
DISPLAY INVISIBLE (-2175 2875);
FORCEPROP 1 LAST LOCATION R722
J 2
(-2225 2875);
DISPLAY 0.702128 (-2225 2875);
PAINT YELLOW (-2225 2875);
FORCEPROP 0 LAST $SEC 1
J 0
(-2225 2925);
DISPLAY 0.680851 (-2225 2925);
PAINT MONO (-2225 2925);
DISPLAY INVISIBLE (-2225 2925);
FORCEPROP 0 LAST CDS_SEC 1
J 0
(-2225 2925);
DISPLAY 1.021277 (-2225 2925);
DISPLAY INVISIBLE (-2225 2925);
FORCEPROP 1 LASTPIN (-2075 2875) $PN 1
J 2
(-2087 2887);
DISPLAY 0.808511 (-2087 2887);
PAINT WHITE (-2087 2887);
DISPLAY INVISIBLE (-2087 2887);
FORCEPROP 1 LASTPIN (-2275 2875) $PN 2
J 2
(-2237 2887);
DISPLAY 0.808511 (-2237 2887);
PAINT WHITE (-2237 2887);
DISPLAY INVISIBLE (-2237 2887);
FORCEADD Q_RES..1
(3800 2575);
FORCEPROP 1 LAST VALUE 33.2
J 0
(3900 2575);
DISPLAY 0.510638 (3900 2575);
PAINT SKYBLUE (3900 2575);
FORCEPROP 1 LAST MATERIAL CHIP
J 0
(4000 2575);
DISPLAY 0.510638 (4000 2575);
PAINT SKYBLUE (4000 2575);
FORCEPROP 1 LAST TOLERANCE 1%
J 0
(3925 2575);
DISPLAY 0.510638 (3925 2575);
PAINT SKYBLUE (3925 2575);
DISPLAY INVISIBLE (3925 2575);
FORCEPROP 1 LAST PART_NUMBER CS03322FB03
J 0
(3750 2675);
DISPLAY 0.510638 (3750 2675);
PAINT WHITE (3750 2675);
DISPLAY INVISIBLE (3750 2675);
FORCEPROP 1 LAST PACK_TYPE 0402LF
J 0
(4050 2425);
DISPLAY 0.510638 (4050 2425);
PAINT SKYBLUE (4050 2425);
DISPLAY INVISIBLE (4050 2425);
FORCEPROP 1 LAST WATTAGE 1/16W
J 2
(3775 2425);
DISPLAY 0.510638 (3775 2425);
PAINT SKYBLUE (3775 2425);
DISPLAY INVISIBLE (3775 2425);
FORCEPROP 1 LAST PATH I351
J 0
(3750 2725);
DISPLAY 0.978723 (3750 2725);
PAINT WHITE (3750 2725);
DISPLAY INVISIBLE (3750 2725);
FORCEPROP 2 LAST CDS_LIB pure_quanta
J 0
(3800 2575);
DISPLAY INVISIBLE (3800 2575);
FORCEPROP 1 LAST LOCATION R826
J 0
(3600 2575);
DISPLAY 0.702128 (3600 2575);
PAINT YELLOW (3600 2575);
FORCEPROP 1 LASTPIN (3700 2575) $PN 1
J 0
(3712 2587);
DISPLAY 0.808511 (3712 2587);
PAINT WHITE (3712 2587);
FORCEPROP 1 LASTPIN (3900 2575) $PN 2
J 0
(3862 2587);
DISPLAY 0.808511 (3862 2587);
PAINT WHITE (3862 2587);
FORCEPROP 2 LAST $SEC 1
J 0
(3750 2775);
DISPLAY 0.680851 (3750 2775);
PAINT MONO (3750 2775);
DISPLAY INVISIBLE (3750 2775);
FORCEPROP 0 LAST CDS_SEC 1
J 0
(3750 2775);
DISPLAY 0.680851 (3750 2775);
PAINT MONO (3750 2775);
DISPLAY INVISIBLE (3750 2775);
FORCEADD OFFPAGE..2
(4100 450);
FORCEPROP 2 LAST $XR1 34 
J 0
(4379 450);
DISPLAY 0.638298 (4379 450);
PAINT MONO (4379 450);
FORCEPROP 2 LAST $XR0 13 
J 0
(4289 450);
DISPLAY 0.638298 (4289 450);
PAINT MONO (4289 450);
FORCEPROP 2 LAST PATH I352
J 0
(4400 500);
DISPLAY 0.680851 (4400 500);
DISPLAY INVISIBLE (4400 500);
FORCEPROP 1 LAST COMMENT_BODY TRUE
J 0
(4055 355);
DISPLAY 0.872340 (4055 355);
PAINT PEACH (4055 355);
DISPLAY INVISIBLE (4055 355);
FORCEPROP 1 LAST OFFPAGE TRUE
J 0
(4425 325);
DISPLAY 0.872340 (4425 325);
PAINT GREEN (4425 325);
DISPLAY INVISIBLE (4425 325);
FORCEPROP 2 LAST CDS_LIB standard
J 0
(4100 450);
DISPLAY INVISIBLE (4100 450);
FORCEADD Q_RES..1
(2750 450);
FORCEPROP 1 LAST MATERIAL CHIP
J 0
(3125 450);
DISPLAY 0.510638 (3125 450);
PAINT SKYBLUE (3125 450);
FORCEPROP 1 LAST VALUE 4.7K
J 2
(3025 450);
DISPLAY 0.510638 (3025 450);
PAINT SKYBLUE (3025 450);
FORCEPROP 1 LAST PART_NUMBER CS24702FB06
J 0
(2700 550);
DISPLAY 0.510638 (2700 550);
PAINT WHITE (2700 550);
DISPLAY INVISIBLE (2700 550);
FORCEPROP 1 LAST PACK_TYPE 0402LF
J 0
(3000 300);
DISPLAY 0.510638 (3000 300);
PAINT SKYBLUE (3000 300);
DISPLAY INVISIBLE (3000 300);
FORCEPROP 1 LAST WATTAGE 1/16W
J 2
(2725 300);
DISPLAY 0.510638 (2725 300);
PAINT SKYBLUE (2725 300);
DISPLAY INVISIBLE (2725 300);
FORCEPROP 1 LAST PATH I353
J 0
(2700 600);
DISPLAY 0.978723 (2700 600);
PAINT WHITE (2700 600);
DISPLAY INVISIBLE (2700 600);
FORCEPROP 1 LAST TOLERANCE 1%
J 0
(2750 350);
DISPLAY 0.510638 (2750 350);
PAINT SKYBLUE (2750 350);
DISPLAY INVISIBLE (2750 350);
FORCEPROP 2 LAST CDS_LIB pure_quanta
J 0
(2750 450);
DISPLAY INVISIBLE (2750 450);
FORCEPROP 1 LAST LOCATION R816
J 2
(2600 450);
DISPLAY 0.702128 (2600 450);
PAINT YELLOW (2600 450);
FORCEPROP 0 LAST $SEC 1
J 0
(2400 500);
DISPLAY INVISIBLE (2400 500);
FORCEPROP 0 LAST CDS_SEC 1
J 0
(2400 500);
DISPLAY INVISIBLE (2400 500);
FORCEPROP 1 LASTPIN (2650 450) $PN 1
J 0
(2662 462);
DISPLAY 0.808511 (2662 462);
PAINT WHITE (2662 462);
DISPLAY INVISIBLE (2662 462);
FORCEPROP 1 LASTPIN (2850 450) $PN 2
J 0
(2812 462);
DISPLAY 0.808511 (2812 462);
PAINT WHITE (2812 462);
DISPLAY INVISIBLE (2812 462);
FORCEADD UNIVERSAL_POWER..1
(1050 100);
FORCEPROP 3 LASTPIN (1050 50) SIG_NAME P3V3_AUX\g
J 0
(1060 60);
DISPLAY 0.659574 (1060 60);
PAINT MONO (1060 60);
DISPLAY INVISIBLE (1060 60);
FORCEPROP 1 LAST HDL_POWER P3V3_AUX
J 1
(1050 150);
DISPLAY 0.702128 (1050 150);
PAINT GREEN (1050 150);
FORCEPROP 1 LAST PATH I355
J 0
(1100 125);
DISPLAY 0.872340 (1100 125);
PAINT AQUA (1100 125);
DISPLAY INVISIBLE (1100 125);
FORCEPROP 2 LAST CDS_LIB logical_power
J 0
(1050 100);
DISPLAY INVISIBLE (1050 100);
FORCEADD Q_RES..1
(1300 -50);
FORCEPROP 1 LAST MATERIAL CHIP
J 0
(1675 -50);
DISPLAY 0.510638 (1675 -50);
PAINT SKYBLUE (1675 -50);
FORCEPROP 1 LAST VALUE 4.7K
J 2
(1575 -50);
DISPLAY 0.510638 (1575 -50);
PAINT SKYBLUE (1575 -50);
FORCEPROP 1 LAST PART_NUMBER CS24702FB06
J 0
(1250 50);
DISPLAY 0.510638 (1250 50);
PAINT WHITE (1250 50);
DISPLAY INVISIBLE (1250 50);
FORCEPROP 1 LAST WATTAGE 1/16W
J 2
(1275 -200);
DISPLAY 0.510638 (1275 -200);
PAINT SKYBLUE (1275 -200);
DISPLAY INVISIBLE (1275 -200);
FORCEPROP 1 LAST PATH I356
J 0
(1250 100);
DISPLAY 0.978723 (1250 100);
PAINT WHITE (1250 100);
DISPLAY INVISIBLE (1250 100);
FORCEPROP 1 LAST TOLERANCE 1%
J 0
(1300 -150);
DISPLAY 0.510638 (1300 -150);
PAINT SKYBLUE (1300 -150);
DISPLAY INVISIBLE (1300 -150);
FORCEPROP 2 LAST CDS_LIB pure_quanta
J 0
(1300 -50);
DISPLAY INVISIBLE (1300 -50);
FORCEPROP 1 LAST PACK_TYPE 0402LF
J 0
(1550 -200);
DISPLAY 0.510638 (1550 -200);
PAINT SKYBLUE (1550 -200);
DISPLAY INVISIBLE (1550 -200);
FORCEPROP 2 LAST SEC_TYPE 0402LF
J 0
(1250 150);
DISPLAY 0.680851 (1250 150);
DISPLAY INVISIBLE (1250 150);
FORCEPROP 1 LAST LOCATION R805
J 2
(1150 -50);
DISPLAY 0.702128 (1150 -50);
PAINT YELLOW (1150 -50);
FORCEPROP 1 LASTPIN (1200 -50) $PN 1
J 0
(1212 -38);
DISPLAY 0.808511 (1212 -38);
PAINT WHITE (1212 -38);
FORCEPROP 1 LASTPIN (1400 -50) $PN 2
J 0
(1362 -38);
DISPLAY 0.808511 (1362 -38);
PAINT WHITE (1362 -38);
FORCEPROP 0 LAST SEC 1
J 0
(950 0);
DISPLAY INVISIBLE (950 0);
FORCEADD OFFPAGE..2
(4475 4025);
FORCEPROP 2 LAST $XR0 46 
J 0
(4664 4025);
DISPLAY 0.638298 (4664 4025);
PAINT MONO (4664 4025);
FORCEPROP 2 LAST CDS_LIB standard
J 0
(4475 4025);
DISPLAY INVISIBLE (4475 4025);
FORCEPROP 1 LAST COMMENT_BODY TRUE
J 0
(4430 3930);
DISPLAY 0.872340 (4430 3930);
PAINT PEACH (4430 3930);
DISPLAY INVISIBLE (4430 3930);
FORCEPROP 1 LAST OFFPAGE TRUE
J 0
(4800 3900);
DISPLAY 0.872340 (4800 3900);
PAINT GREEN (4800 3900);
DISPLAY INVISIBLE (4800 3900);
FORCEPROP 2 LAST PATH I358
J 0
(4650 4100);
DISPLAY 0.680851 (4650 4100);
DISPLAY INVISIBLE (4650 4100);
FORCEADD OFFPAGE..2
(4475 3975);
FORCEPROP 2 LAST $XR1 46 
J 0
(4754 3975);
DISPLAY 0.638298 (4754 3975);
PAINT MONO (4754 3975);
FORCEPROP 2 LAST $XR0 27 
J 0
(4664 3975);
DISPLAY 0.638298 (4664 3975);
PAINT MONO (4664 3975);
FORCEPROP 2 LAST PATH I359
J 0
(4650 4050);
DISPLAY 0.680851 (4650 4050);
DISPLAY INVISIBLE (4650 4050);
FORCEPROP 1 LAST OFFPAGE TRUE
J 0
(4800 3850);
DISPLAY 0.872340 (4800 3850);
PAINT GREEN (4800 3850);
DISPLAY INVISIBLE (4800 3850);
FORCEPROP 1 LAST COMMENT_BODY TRUE
J 0
(4430 3880);
DISPLAY 0.872340 (4430 3880);
PAINT PEACH (4430 3880);
DISPLAY INVISIBLE (4430 3880);
FORCEPROP 2 LAST CDS_LIB standard
J 0
(4475 3975);
DISPLAY INVISIBLE (4475 3975);
FORCEADD Q_RES..1
(3250 3975);
FORCEPROP 1 LAST VALUE 33.2
J 2
(3425 3975);
DISPLAY 0.510638 (3425 3975);
PAINT SKYBLUE (3425 3975);
FORCEPROP 1 LAST MATERIAL CHIP
J 0
(3450 3975);
DISPLAY 0.510638 (3450 3975);
PAINT SKYBLUE (3450 3975);
FORCEPROP 1 LAST PATH I360
J 0
(3200 4125);
DISPLAY 0.978723 (3200 4125);
PAINT WHITE (3200 4125);
DISPLAY INVISIBLE (3200 4125);
FORCEPROP 2 LAST CDS_LIB pure_quanta
J 0
(3250 3975);
DISPLAY INVISIBLE (3250 3975);
FORCEPROP 1 LAST WATTAGE 1/16W
J 2
(3600 4075);
DISPLAY 0.510638 (3600 4075);
PAINT SKYBLUE (3600 4075);
DISPLAY INVISIBLE (3600 4075);
FORCEPROP 1 LAST PACK_TYPE 0402LF
J 0
(3225 4025);
DISPLAY 0.510638 (3225 4025);
PAINT SKYBLUE (3225 4025);
DISPLAY INVISIBLE (3225 4025);
FORCEPROP 1 LAST PART_NUMBER CS03322FB03
J 0
(3150 4050);
DISPLAY 0.510638 (3150 4050);
PAINT WHITE (3150 4050);
DISPLAY INVISIBLE (3150 4050);
FORCEPROP 1 LAST TOLERANCE 1%
J 0
(3175 4075);
DISPLAY 0.510638 (3175 4075);
PAINT SKYBLUE (3175 4075);
DISPLAY INVISIBLE (3175 4075);
FORCEPROP 1 LAST $LOCATION R309
J 0
(3025 3975);
DISPLAY 0.702128 (3025 3975);
PAINT YELLOW (3025 3975);
FORCEPROP 0 LAST CDS_LOCATION R309
J 0
(3025 4025);
DISPLAY 0.680851 (3025 4025);
DISPLAY INVISIBLE (3025 4025);
FORCEPROP 0 LAST $SEC 1
J 0
(3025 4025);
DISPLAY 0.680851 (3025 4025);
PAINT MONO (3025 4025);
DISPLAY INVISIBLE (3025 4025);
FORCEPROP 0 LAST CDS_SEC 1
J 0
(3025 4025);
DISPLAY 1.021277 (3025 4025);
DISPLAY INVISIBLE (3025 4025);
FORCEPROP 1 LASTPIN (3150 3975) $PN 1
J 0
(3162 3987);
DISPLAY 0.808511 (3162 3987);
PAINT WHITE (3162 3987);
DISPLAY INVISIBLE (3162 3987);
FORCEPROP 1 LASTPIN (3350 3975) $PN 2
J 0
(3312 3987);
DISPLAY 0.808511 (3312 3987);
PAINT WHITE (3312 3987);
DISPLAY INVISIBLE (3312 3987);
FORCEADD AST2600A3GP..2
(725 2675);
FORCEPROP 1 LAST PART_NUMBER AJ026000T06
J 0
(-295 4527);
DISPLAY 0.723404 (-295 4527);
FORCEPROP 2 LAST PART_TYPE SMLF
J 0
(-275 4775);
DISPLAY 0.680851 (-275 4775);
FORCEPROP 1 LAST MATERIAL IC
J 0
(-295 4400);
DISPLAY 0.723404 (-295 4400);
FORCEPROP 2 LAST VALUE AST2600A3-GP
J 0
(-275 4725);
DISPLAY 0.680851 (-275 4725);
FORCEPROP 2 LAST CDS_LIB pure_quanta
J 0
(725 2675);
DISPLAY INVISIBLE (725 2675);
FORCEPROP 1 LAST PATH I363
J 0
(725 2675);
DISPLAY 0.723404 (725 2675);
DISPLAY INVISIBLE (725 2675);
FORCEPROP 1 LAST CDS_LMAN_SYM_OUTLINE -1025,1700,1025,-1700
J 0
(725 2675);
DISPLAY 0.468085 (725 2675);
PAINT GREEN (725 2675);
DISPLAY INVISIBLE (725 2675);
FORCEPROP 1 LAST NEEDS_NO_SIZE TRUE
J 0
(725 2675);
DISPLAY 0.723404 (725 2675);
DISPLAY INVISIBLE (725 2675);
FORCEPROP 1 LAST LOCATION U5
J 0
(-295 4674);
DISPLAY 0.723404 (-295 4674);
FORCEPROP 0 LASTPIN (1900 4325) $PN AF13
J 0
(1910 4335);
DISPLAY 0.680851 (1910 4335);
PAINT MONO (1910 4335);
FORCEPROP 0 LASTPIN (-450 4325) $PN AB14
J 2
(-460 4335);
DISPLAY 0.680851 (-460 4335);
PAINT MONO (-460 4335);
FORCEPROP 0 LASTPIN (-450 4275) $PN AA13
J 2
(-460 4285);
DISPLAY 0.680851 (-460 4285);
PAINT MONO (-460 4285);
FORCEPROP 0 LASTPIN (-450 4225) $PN AC13
J 2
(-460 4235);
DISPLAY 0.680851 (-460 4235);
PAINT MONO (-460 4235);
FORCEPROP 0 LASTPIN (1900 4225) $PN AB13
J 0
(1910 4235);
DISPLAY 0.680851 (1910 4235);
PAINT MONO (1910 4235);
FORCEPROP 0 LASTPIN (1900 4275) $PN AC14
J 0
(1910 4285);
DISPLAY 0.680851 (1910 4285);
PAINT MONO (1910 4285);
FORCEPROP 0 LASTPIN (-450 3375) $PN J26
J 2
(-460 3385);
DISPLAY 0.680851 (-460 3385);
PAINT MONO (-460 3385);
FORCEPROP 0 LASTPIN (-450 3325) $PN K23
J 2
(-460 3335);
DISPLAY 0.680851 (-460 3335);
PAINT MONO (-460 3335);
FORCEPROP 0 LASTPIN (-450 3275) $PN H26
J 2
(-460 3285);
DISPLAY 0.680851 (-460 3285);
PAINT MONO (-460 3285);
FORCEPROP 0 LASTPIN (-450 3225) $PN J25
J 2
(-460 3235);
DISPLAY 0.680851 (-460 3235);
PAINT MONO (-460 3235);
FORCEPROP 0 LASTPIN (-450 3175) $PN J23
J 2
(-460 3185);
DISPLAY 0.680851 (-460 3185);
PAINT MONO (-460 3185);
FORCEPROP 0 LASTPIN (-450 3125) $PN G26
J 2
(-460 3135);
DISPLAY 0.680851 (-460 3135);
PAINT MONO (-460 3135);
FORCEPROP 0 LASTPIN (-450 3075) $PN H25
J 2
(-460 3085);
DISPLAY 0.680851 (-460 3085);
PAINT MONO (-460 3085);
FORCEPROP 0 LASTPIN (-450 3025) $PN J24
J 2
(-460 3035);
DISPLAY 0.680851 (-460 3035);
PAINT MONO (-460 3035);
FORCEPROP 0 LASTPIN (1900 2625) $PN E16
J 0
(1910 2635);
DISPLAY 0.680851 (1910 2635);
PAINT MONO (1910 2635);
FORCEPROP 0 LASTPIN (-450 2625) $PN B16
J 2
(-460 2635);
DISPLAY 0.680851 (-460 2635);
PAINT MONO (-460 2635);
FORCEPROP 0 LASTPIN (1900 2575) $PN A15
J 0
(1910 2585);
DISPLAY 0.680851 (1910 2585);
PAINT MONO (1910 2585);
FORCEPROP 0 LASTPIN (-450 2025) $PN C15
J 2
(-460 2035);
DISPLAY 0.680851 (-460 2035);
PAINT MONO (-460 2035);
FORCEPROP 0 LASTPIN (-450 1975) $PN F15
J 2
(-460 1985);
DISPLAY 0.680851 (-460 1985);
PAINT MONO (-460 1985);
FORCEPROP 0 LASTPIN (-450 2475) $PN D14
J 2
(-460 2485);
DISPLAY 0.680851 (-460 2485);
PAINT MONO (-460 2485);
FORCEPROP 0 LASTPIN (-450 2425) $PN B13
J 2
(-460 2435);
DISPLAY 0.680851 (-460 2435);
PAINT MONO (-460 2435);
FORCEPROP 0 LASTPIN (-450 2375) $PN A12
J 2
(-460 2385);
DISPLAY 0.680851 (-460 2385);
PAINT MONO (-460 2385);
FORCEPROP 0 LASTPIN (-450 2325) $PN E14
J 2
(-460 2335);
DISPLAY 0.680851 (-460 2335);
PAINT MONO (-460 2335);
FORCEPROP 0 LASTPIN (-450 2275) $PN B12
J 2
(-460 2285);
DISPLAY 0.680851 (-460 2285);
PAINT MONO (-460 2285);
FORCEPROP 0 LASTPIN (-450 2225) $PN C12
J 2
(-460 2235);
DISPLAY 0.680851 (-460 2235);
PAINT MONO (-460 2235);
FORCEPROP 0 LASTPIN (-450 2175) $PN C13
J 2
(-460 2185);
DISPLAY 0.680851 (-460 2185);
PAINT MONO (-460 2185);
FORCEPROP 0 LASTPIN (-450 2125) $PN D13
J 2
(-460 2135);
DISPLAY 0.680851 (-460 2135);
PAINT MONO (-460 2135);
FORCEPROP 0 LASTPIN (1900 2475) $PN P25
J 0
(1910 2485);
DISPLAY 0.680851 (1910 2485);
PAINT MONO (1910 2485);
FORCEPROP 0 LASTPIN (1900 2425) $PN N23
J 0
(1910 2435);
DISPLAY 0.680851 (1910 2435);
PAINT MONO (1910 2435);
FORCEPROP 0 LASTPIN (1900 2375) $PN N25
J 0
(1910 2385);
DISPLAY 0.680851 (1910 2385);
PAINT MONO (1910 2385);
FORCEPROP 0 LASTPIN (1900 2325) $PN N24
J 0
(1910 2335);
DISPLAY 0.680851 (1910 2335);
PAINT MONO (1910 2335);
FORCEPROP 0 LASTPIN (1900 2275) $PN P26
J 0
(1910 2285);
DISPLAY 0.680851 (1910 2285);
PAINT MONO (1910 2285);
FORCEPROP 0 LASTPIN (1900 2225) $PN M23
J 0
(1910 2235);
DISPLAY 0.680851 (1910 2235);
PAINT MONO (1910 2235);
FORCEPROP 0 LASTPIN (1900 2175) $PN N26
J 0
(1910 2185);
DISPLAY 0.680851 (1910 2185);
PAINT MONO (1910 2185);
FORCEPROP 0 LASTPIN (1900 2125) $PN M26
J 0
(1910 2135);
DISPLAY 0.680851 (1910 2135);
PAINT MONO (1910 2135);
FORCEPROP 0 LASTPIN (1900 1075) $PN R23
J 0
(1910 1085);
DISPLAY 0.680851 (1910 1085);
PAINT MONO (1910 1085);
FORCEPROP 0 LASTPIN (1900 1025) $PN T25
J 0
(1910 1035);
DISPLAY 0.680851 (1910 1035);
PAINT MONO (1910 1035);
FORCEPROP 0 LASTPIN (1900 3375) $PN R26
J 0
(1910 3385);
DISPLAY 0.680851 (1910 3385);
PAINT MONO (1910 3385);
FORCEPROP 0 LASTPIN (1900 3325) $PN P24
J 0
(1910 3335);
DISPLAY 0.680851 (1910 3335);
PAINT MONO (1910 3335);
FORCEPROP 0 LASTPIN (1900 3275) $PN P23
J 0
(1910 3285);
DISPLAY 0.680851 (1910 3285);
PAINT MONO (1910 3285);
FORCEPROP 0 LASTPIN (1900 3225) $PN T24
J 0
(1910 3235);
DISPLAY 0.680851 (1910 3235);
PAINT MONO (1910 3235);
FORCEPROP 0 LASTPIN (-450 2875) $PN AB15
J 2
(-460 2885);
DISPLAY 0.680851 (-460 2885);
PAINT MONO (-460 2885);
FORCEPROP 0 LASTPIN (-450 2825) $PN AF14
J 2
(-460 2835);
DISPLAY 0.680851 (-460 2835);
PAINT MONO (-460 2835);
FORCEPROP 0 LASTPIN (-450 2775) $PN AD14
J 2
(-460 2785);
DISPLAY 0.680851 (-460 2785);
PAINT MONO (-460 2785);
FORCEPROP 0 LASTPIN (-450 2725) $PN AC15
J 2
(-460 2735);
DISPLAY 0.680851 (-460 2735);
PAINT MONO (-460 2735);
FORCEPROP 0 LASTPIN (1900 2875) $PN AE15
J 0
(1910 2885);
DISPLAY 0.680851 (1910 2885);
PAINT MONO (1910 2885);
FORCEPROP 0 LASTPIN (1900 2825) $PN AE14
J 0
(1910 2835);
DISPLAY 0.680851 (1910 2835);
PAINT MONO (1910 2835);
FORCEPROP 0 LASTPIN (1900 2775) $PN AD15
J 0
(1910 2785);
DISPLAY 0.680851 (1910 2785);
PAINT MONO (1910 2785);
FORCEPROP 0 LASTPIN (1900 2725) $PN AF15
J 0
(1910 2735);
DISPLAY 0.680851 (1910 2735);
PAINT MONO (1910 2735);
FORCEPROP 0 LASTPIN (-450 3725) $PN AE8
J 2
(-460 3735);
DISPLAY 0.680851 (-460 3735);
PAINT MONO (-460 3735);
FORCEPROP 0 LASTPIN (-450 3675) $PN AA9
J 2
(-460 3685);
DISPLAY 0.680851 (-460 3685);
PAINT MONO (-460 3685);
FORCEPROP 0 LASTPIN (-450 3625) $PN AC9
J 2
(-460 3635);
DISPLAY 0.680851 (-460 3635);
PAINT MONO (-460 3635);
FORCEPROP 0 LASTPIN (1900 3725) $PN AF8
J 0
(1910 3735);
DISPLAY 0.680851 (1910 3735);
PAINT MONO (1910 3735);
FORCEPROP 0 LASTPIN (1900 3675) $PN AB9
J 0
(1910 3685);
DISPLAY 0.680851 (1910 3685);
PAINT MONO (1910 3685);
FORCEPROP 0 LASTPIN (1900 3625) $PN AD9
J 0
(1910 3635);
DISPLAY 0.680851 (1910 3635);
PAINT MONO (1910 3635);
FORCEPROP 0 LASTPIN (1900 3575) $PN AF9
J 0
(1910 3585);
DISPLAY 0.680851 (1910 3585);
PAINT MONO (1910 3585);
FORCEPROP 0 LASTPIN (1900 3525) $PN AB10
J 0
(1910 3535);
DISPLAY 0.680851 (1910 3535);
PAINT MONO (1910 3535);
FORCEPROP 0 LASTPIN (1900 3175) $PN AF11
J 0
(1910 3185);
DISPLAY 0.680851 (1910 3185);
PAINT MONO (1910 3185);
FORCEPROP 0 LASTPIN (1900 3125) $PN AD12
J 0
(1910 3135);
DISPLAY 0.680851 (1910 3135);
PAINT MONO (1910 3135);
FORCEPROP 0 LASTPIN (1900 3075) $PN AE11
J 0
(1910 3085);
DISPLAY 0.680851 (1910 3085);
PAINT MONO (1910 3085);
FORCEPROP 0 LASTPIN (1900 3025) $PN AA12
J 0
(1910 3035);
DISPLAY 0.680851 (1910 3035);
PAINT MONO (1910 3035);
FORCEPROP 0 LASTPIN (1900 4175) $PN AE12
J 0
(1910 4185);
DISPLAY 0.680851 (1910 4185);
PAINT MONO (1910 4185);
FORCEPROP 0 LASTPIN (1900 4125) $PN AF12
J 0
(1910 4135);
DISPLAY 0.680851 (1910 4135);
PAINT MONO (1910 4135);
FORCEPROP 0 LASTPIN (-450 4175) $PN AC12
J 2
(-460 4185);
DISPLAY 0.680851 (-460 4185);
PAINT MONO (-460 4185);
FORCEPROP 0 LASTPIN (-450 4125) $PN AB12
J 2
(-460 4135);
DISPLAY 0.680851 (-460 4135);
PAINT MONO (-460 4135);
FORCEPROP 0 LASTPIN (-450 3975) $PN AC10
J 2
(-460 3985);
DISPLAY 0.680851 (-460 3985);
PAINT MONO (-460 3985);
FORCEPROP 0 LASTPIN (-450 3875) $PN AD10
J 2
(-460 3885);
DISPLAY 0.680851 (-460 3885);
PAINT MONO (-460 3885);
FORCEPROP 0 LASTPIN (-450 3825) $PN AE10
J 2
(-460 3835);
DISPLAY 0.680851 (-460 3835);
PAINT MONO (-460 3835);
FORCEPROP 0 LASTPIN (1900 4025) $PN AB11
J 0
(1910 4035);
DISPLAY 0.680851 (1910 4035);
PAINT MONO (1910 4035);
FORCEPROP 0 LASTPIN (1900 3975) $PN AC11
J 0
(1910 3985);
DISPLAY 0.680851 (1910 3985);
PAINT MONO (1910 3985);
FORCEPROP 0 LASTPIN (1900 3925) $PN AA11
J 0
(1910 3935);
DISPLAY 0.680851 (1910 3935);
PAINT MONO (1910 3935);
FORCEPROP 0 LASTPIN (1900 3875) $PN AD11
J 0
(1910 3885);
DISPLAY 0.680851 (1910 3885);
PAINT MONO (1910 3885);
FORCEPROP 0 LASTPIN (1900 3825) $PN AF10
J 0
(1910 3835);
DISPLAY 0.680851 (1910 3835);
PAINT MONO (1910 3835);
FORCEPROP 0 LASTPIN (-450 1425) $PN G23
J 2
(-460 1435);
DISPLAY 0.680851 (-460 1435);
PAINT MONO (-460 1435);
FORCEPROP 0 LASTPIN (-450 1375) $PN G24
J 2
(-460 1385);
DISPLAY 0.680851 (-460 1385);
PAINT MONO (-460 1385);
FORCEPROP 0 LASTPIN (-450 1325) $PN F23
J 2
(-460 1335);
DISPLAY 0.680851 (-460 1335);
PAINT MONO (-460 1335);
FORCEPROP 0 LASTPIN (-450 1275) $PN F26
J 2
(-460 1285);
DISPLAY 0.680851 (-460 1285);
PAINT MONO (-460 1285);
FORCEPROP 0 LASTPIN (-450 1225) $PN F25
J 2
(-460 1235);
DISPLAY 0.680851 (-460 1235);
PAINT MONO (-460 1235);
FORCEPROP 0 LASTPIN (-450 1175) $PN E26
J 2
(-460 1185);
DISPLAY 0.680851 (-460 1185);
PAINT MONO (-460 1185);
FORCEPROP 0 LASTPIN (1900 1425) $PN H24
J 0
(1910 1435);
DISPLAY 0.680851 (1910 1435);
PAINT MONO (1910 1435);
FORCEPROP 0 LASTPIN (1900 1375) $PN J22
J 0
(1910 1385);
DISPLAY 0.680851 (1910 1385);
PAINT MONO (1910 1385);
FORCEPROP 0 LASTPIN (1900 1325) $PN H22
J 0
(1910 1335);
DISPLAY 0.680851 (1910 1335);
PAINT MONO (1910 1335);
FORCEPROP 0 LASTPIN (1900 1275) $PN H23
J 0
(1910 1285);
DISPLAY 0.680851 (1910 1285);
PAINT MONO (1910 1285);
FORCEPROP 0 LASTPIN (1900 1225) $PN G22
J 0
(1910 1235);
DISPLAY 0.680851 (1910 1235);
PAINT MONO (1910 1235);
FORCEPROP 0 LASTPIN (1900 1175) $PN F22
J 0
(1910 1185);
DISPLAY 0.680851 (1910 1185);
PAINT MONO (1910 1185);
FORCEPROP 0 LASTPIN (-450 1825) $PN C25
J 2
(-460 1835);
DISPLAY 0.680851 (-460 1835);
PAINT MONO (-460 1835);
FORCEPROP 0 LASTPIN (-450 1775) $PN C26
J 2
(-460 1785);
DISPLAY 0.680851 (-460 1785);
PAINT MONO (-460 1785);
FORCEPROP 0 LASTPIN (-450 1725) $PN C24
J 2
(-460 1735);
DISPLAY 0.680851 (-460 1735);
PAINT MONO (-460 1735);
FORCEPROP 0 LASTPIN (-450 1675) $PN B26
J 2
(-460 1685);
DISPLAY 0.680851 (-460 1685);
PAINT MONO (-460 1685);
FORCEPROP 0 LASTPIN (-450 1625) $PN B25
J 2
(-460 1635);
DISPLAY 0.680851 (-460 1635);
PAINT MONO (-460 1635);
FORCEPROP 0 LASTPIN (-450 1575) $PN B24
J 2
(-460 1585);
DISPLAY 0.680851 (-460 1585);
PAINT MONO (-460 1585);
FORCEPROP 0 LASTPIN (1900 1825) $PN F24
J 0
(1910 1835);
DISPLAY 0.680851 (1910 1835);
PAINT MONO (1910 1835);
FORCEPROP 0 LASTPIN (1900 1775) $PN E23
J 0
(1910 1785);
DISPLAY 0.680851 (1910 1785);
PAINT MONO (1910 1785);
FORCEPROP 0 LASTPIN (1900 1725) $PN E24
J 0
(1910 1735);
DISPLAY 0.680851 (1910 1735);
PAINT MONO (1910 1735);
FORCEPROP 0 LASTPIN (1900 1675) $PN E25
J 0
(1910 1685);
DISPLAY 0.680851 (1910 1685);
PAINT MONO (1910 1685);
FORCEPROP 0 LASTPIN (1900 1625) $PN D26
J 0
(1910 1635);
DISPLAY 0.680851 (1910 1635);
PAINT MONO (1910 1635);
FORCEPROP 0 LASTPIN (1900 1575) $PN D24
J 0
(1910 1585);
DISPLAY 0.680851 (1910 1585);
PAINT MONO (1910 1585);
FORCEPROP 0 LASTPIN (-450 1025) $PN A10
J 2
(-460 1035);
DISPLAY 0.680851 (-460 1035);
PAINT MONO (-460 1035);
FORCEPROP 0 LASTPIN (1900 1975) $PN D8
J 0
(1910 1985);
DISPLAY 0.680851 (1910 1985);
PAINT MONO (1910 1985);
FORCEPROP 0 LASTPIN (-450 4025) $PN AD13
J 2
(-460 4035);
DISPLAY 0.680851 (-460 4035);
PAINT MONO (-460 4035);
FORCEPROP 0 LASTPIN (1900 2025) $PN C8
J 0
(1910 2035);
DISPLAY 0.680851 (1910 2035);
PAINT MONO (1910 2035);
FORCEPROP 0 LAST $SEC 2
J 0
(-275 4825);
DISPLAY 0.680851 (-275 4825);
PAINT MONO (-275 4825);
DISPLAY INVISIBLE (-275 4825);
FORCEPROP 0 LAST CDS_SEC 2
J 0
(-275 4825);
DISPLAY 0.680851 (-275 4825);
DISPLAY INVISIBLE (-275 4825);
FORCEADD OFFPAGE..6
(-2975 2775);
FORCEPROP 2 LAST $XR1 49 
J 0
(-3344 2775);
DISPLAY 0.638298 (-3344 2775);
PAINT MONO (-3344 2775);
FORCEPROP 2 LAST $XR0 42 
J 0
(-3254 2775);
DISPLAY 0.638298 (-3254 2775);
PAINT MONO (-3254 2775);
FORCEPROP 2 LAST PATH I364
J 0
(-3250 2825);
DISPLAY 0.680851 (-3250 2825);
DISPLAY INVISIBLE (-3250 2825);
FORCEPROP 2 LAST CDS_LIB standard
J 0
(-2975 2775);
DISPLAY INVISIBLE (-2975 2775);
FORCEPROP 1 LAST OFFPAGE TRUE
J 0
(-2650 2650);
DISPLAY 0.872340 (-2650 2650);
DISPLAY INVISIBLE (-2650 2650);
FORCEPROP 1 LAST COMMENT_BODY TRUE
J 0
(-2875 2700);
DISPLAY 0.872340 (-2875 2700);
PAINT GREEN (-2875 2700);
DISPLAY INVISIBLE (-2875 2700);
FORCEADD Q_RES..1
(-1775 2775);
FORCEPROP 1 LAST MATERIAL CHIP
J 0
(-1575 2775);
DISPLAY 0.510638 (-1575 2775);
PAINT SKYBLUE (-1575 2775);
FORCEPROP 1 LAST VALUE 33.2
J 0
(-1675 2775);
DISPLAY 0.510638 (-1675 2775);
PAINT SKYBLUE (-1675 2775);
FORCEPROP 1 LAST PATH I365
J 0
(-1825 2925);
DISPLAY 0.978723 (-1825 2925);
PAINT WHITE (-1825 2925);
DISPLAY INVISIBLE (-1825 2925);
FORCEPROP 2 LAST CDS_LIB pure_quanta
J 0
(-1775 2775);
DISPLAY INVISIBLE (-1775 2775);
FORCEPROP 1 LAST WATTAGE 1/16W
J 2
(-1800 2625);
DISPLAY 0.510638 (-1800 2625);
PAINT SKYBLUE (-1800 2625);
DISPLAY INVISIBLE (-1800 2625);
FORCEPROP 1 LAST PACK_TYPE 0402LF
J 0
(-1525 2625);
DISPLAY 0.510638 (-1525 2625);
PAINT SKYBLUE (-1525 2625);
DISPLAY INVISIBLE (-1525 2625);
FORCEPROP 1 LAST PART_NUMBER CS03322FB03
J 0
(-1825 2875);
DISPLAY 0.510638 (-1825 2875);
PAINT WHITE (-1825 2875);
DISPLAY INVISIBLE (-1825 2875);
FORCEPROP 1 LAST TOLERANCE 1%
J 0
(-1650 2775);
DISPLAY 0.510638 (-1650 2775);
PAINT SKYBLUE (-1650 2775);
DISPLAY INVISIBLE (-1650 2775);
FORCEPROP 1 LAST LOCATION R461
J 0
(-2050 2775);
DISPLAY 0.702128 (-2050 2775);
PAINT YELLOW (-2050 2775);
FORCEPROP 1 LASTPIN (-1875 2775) $PN 1
J 0
(-1863 2787);
DISPLAY 0.808511 (-1863 2787);
PAINT WHITE (-1863 2787);
FORCEPROP 1 LASTPIN (-1675 2775) $PN 2
J 0
(-1713 2787);
DISPLAY 0.808511 (-1713 2787);
PAINT WHITE (-1713 2787);
FORCEPROP 2 LAST $SEC 1
J 0
(-1825 2975);
DISPLAY 0.680851 (-1825 2975);
PAINT MONO (-1825 2975);
DISPLAY INVISIBLE (-1825 2975);
FORCEPROP 0 LAST CDS_SEC 1
J 0
(-1825 2975);
DISPLAY 0.680851 (-1825 2975);
PAINT MONO (-1825 2975);
DISPLAY INVISIBLE (-1825 2975);
FORCEADD OFFPAGE..2
R 2
(-3425 1275);
FORCEPROP 2 LAST $XR0 36 
J 0
(-3649 1275);
DISPLAY 0.638298 (-3649 1275);
PAINT MONO (-3649 1275);
FORCEPROP 2 LAST CDS_LIB standard
J 0
(-3425 1275);
DISPLAY INVISIBLE (-3425 1275);
FORCEPROP 2 LAST PATH I368
J 0
(-3375 1350);
DISPLAY 0.680851 (-3375 1350);
DISPLAY INVISIBLE (-3375 1350);
FORCEPROP 1 LAST OFFPAGE TRUE
J 2
(-3750 1150);
DISPLAY 0.872340 (-3750 1150);
PAINT GREEN (-3750 1150);
DISPLAY INVISIBLE (-3750 1150);
FORCEPROP 1 LAST COMMENT_BODY TRUE
J 2
(-3380 1180);
DISPLAY 0.872340 (-3380 1180);
PAINT PEACH (-3380 1180);
DISPLAY INVISIBLE (-3380 1180);
FORCEADD OFFPAGE..2
R 2
(-3425 1325);
FORCEPROP 2 LAST $XR0 36 
J 0
(-3649 1325);
DISPLAY 0.638298 (-3649 1325);
PAINT MONO (-3649 1325);
FORCEPROP 1 LAST OFFPAGE TRUE
J 2
(-3750 1200);
DISPLAY 0.872340 (-3750 1200);
PAINT GREEN (-3750 1200);
DISPLAY INVISIBLE (-3750 1200);
FORCEPROP 1 LAST COMMENT_BODY TRUE
J 2
(-3380 1230);
DISPLAY 0.872340 (-3380 1230);
PAINT PEACH (-3380 1230);
DISPLAY INVISIBLE (-3380 1230);
FORCEPROP 2 LAST PATH I369
J 0
(-3375 1400);
DISPLAY 0.680851 (-3375 1400);
DISPLAY INVISIBLE (-3375 1400);
FORCEPROP 2 LAST CDS_LIB standard
J 0
(-3425 1325);
DISPLAY INVISIBLE (-3425 1325);
FORCEADD OFFPAGE..2
R 2
(-3425 1425);
FORCEPROP 2 LAST $XR0 10 
J 0
(-3649 1425);
DISPLAY 0.638298 (-3649 1425);
PAINT MONO (-3649 1425);
FORCEPROP 1 LAST OFFPAGE TRUE
J 2
(-3750 1300);
DISPLAY 0.872340 (-3750 1300);
PAINT GREEN (-3750 1300);
DISPLAY INVISIBLE (-3750 1300);
FORCEPROP 1 LAST COMMENT_BODY TRUE
J 2
(-3380 1330);
DISPLAY 0.872340 (-3380 1330);
PAINT PEACH (-3380 1330);
DISPLAY INVISIBLE (-3380 1330);
FORCEPROP 2 LAST PATH I370
J 0
(-3375 1500);
DISPLAY 0.680851 (-3375 1500);
DISPLAY INVISIBLE (-3375 1500);
FORCEPROP 2 LAST CDS_LIB standard
J 0
(-3425 1425);
DISPLAY INVISIBLE (-3425 1425);
FORCEADD OFFPAGE..1
(-2975 4175);
FORCEPROP 2 LAST $XR0 13 
J 0
(-3226 4175);
DISPLAY 0.638298 (-3226 4175);
PAINT MONO (-3226 4175);
FORCEPROP 2 LAST CDS_LIB standard
J 0
(-2975 4175);
DISPLAY INVISIBLE (-2975 4175);
FORCEPROP 2 LAST PATH I371
J 0
(-3225 4225);
DISPLAY 0.680851 (-3225 4225);
DISPLAY INVISIBLE (-3225 4225);
FORCEPROP 1 LAST COMMENT_BODY TRUE
J 0
(-2850 4075);
DISPLAY 0.872340 (-2850 4075);
PAINT PEACH (-2850 4075);
DISPLAY INVISIBLE (-2850 4075);
FORCEPROP 1 LAST OFFPAGE TRUE
J 0
(-2650 4050);
DISPLAY 0.872340 (-2650 4050);
DISPLAY INVISIBLE (-2650 4050);
FORCEADD OFFPAGE..1
(-2975 4125);
FORCEPROP 2 LAST $XR0 13 
J 0
(-3226 4125);
DISPLAY 0.638298 (-3226 4125);
PAINT MONO (-3226 4125);
FORCEPROP 1 LAST COMMENT_BODY TRUE
J 0
(-2850 4025);
DISPLAY 0.872340 (-2850 4025);
PAINT PEACH (-2850 4025);
DISPLAY INVISIBLE (-2850 4025);
FORCEPROP 1 LAST OFFPAGE TRUE
J 0
(-2650 4000);
DISPLAY 0.872340 (-2650 4000);
DISPLAY INVISIBLE (-2650 4000);
FORCEPROP 2 LAST CDS_LIB standard
J 0
(-2975 4125);
DISPLAY INVISIBLE (-2975 4125);
FORCEPROP 2 LAST PATH I372
J 0
(-3225 4175);
DISPLAY 0.680851 (-3225 4175);
DISPLAY INVISIBLE (-3225 4175);
FORCEADD Q_RES..1
(-1775 4125);
FORCEPROP 1 LAST VALUE 33.2
J 0
(-1675 4125);
DISPLAY 0.510638 (-1675 4125);
PAINT SKYBLUE (-1675 4125);
FORCEPROP 1 LAST MATERIAL CHIP
J 0
(-1925 4125);
DISPLAY 0.510638 (-1925 4125);
PAINT SKYBLUE (-1925 4125);
FORCEPROP 1 LAST PACK_TYPE 0402LF
J 0
(-1525 3975);
DISPLAY 0.510638 (-1525 3975);
PAINT SKYBLUE (-1525 3975);
DISPLAY INVISIBLE (-1525 3975);
FORCEPROP 2 LAST CDS_LIB pure_quanta
J 0
(-1775 4125);
DISPLAY INVISIBLE (-1775 4125);
FORCEPROP 1 LAST PATH I373
J 0
(-1825 4275);
DISPLAY 0.978723 (-1825 4275);
PAINT WHITE (-1825 4275);
DISPLAY INVISIBLE (-1825 4275);
FORCEPROP 1 LAST WATTAGE 1/16W
J 2
(-1800 3975);
DISPLAY 0.510638 (-1800 3975);
PAINT SKYBLUE (-1800 3975);
DISPLAY INVISIBLE (-1800 3975);
FORCEPROP 1 LAST PART_NUMBER CS03322FB03
J 0
(-1825 4225);
DISPLAY 0.510638 (-1825 4225);
PAINT WHITE (-1825 4225);
DISPLAY INVISIBLE (-1825 4225);
FORCEPROP 1 LAST TOLERANCE 1%
J 0
(-1650 4125);
DISPLAY 0.510638 (-1650 4125);
PAINT SKYBLUE (-1650 4125);
DISPLAY INVISIBLE (-1650 4125);
FORCEPROP 1 LAST $LOCATION R402
J 0
(-2050 4125);
DISPLAY 0.702128 (-2050 4125);
PAINT YELLOW (-2050 4125);
FORCEPROP 1 LASTPIN (-1875 4125) $PN 1
J 0
(-1863 4137);
DISPLAY 0.787234 (-1863 4137);
PAINT MONO (-1863 4137);
FORCEPROP 1 LASTPIN (-1675 4125) $PN 2
J 0
(-1713 4137);
DISPLAY 0.787234 (-1713 4137);
PAINT MONO (-1713 4137);
FORCEPROP 0 LAST CDS_LOCATION R402
J 0
(-2050 4175);
DISPLAY 0.680851 (-2050 4175);
DISPLAY INVISIBLE (-2050 4175);
FORCEPROP 0 LAST $SEC 1
J 0
(-2050 4175);
DISPLAY 0.680851 (-2050 4175);
PAINT MONO (-2050 4175);
DISPLAY INVISIBLE (-2050 4175);
FORCEPROP 0 LAST CDS_SEC 1
J 0
(-2050 4175);
DISPLAY 0.680851 (-2050 4175);
DISPLAY INVISIBLE (-2050 4175);
FORCEADD Q_RES..1
(-1775 4175);
FORCEPROP 1 LAST VALUE 33.2
J 0
(-1675 4175);
DISPLAY 0.510638 (-1675 4175);
PAINT SKYBLUE (-1675 4175);
FORCEPROP 1 LAST MATERIAL CHIP
J 0
(-1925 4175);
DISPLAY 0.510638 (-1925 4175);
PAINT SKYBLUE (-1925 4175);
FORCEPROP 1 LAST PACK_TYPE 0402LF
J 0
(-1525 4025);
DISPLAY 0.510638 (-1525 4025);
PAINT SKYBLUE (-1525 4025);
DISPLAY INVISIBLE (-1525 4025);
FORCEPROP 2 LAST CDS_LIB pure_quanta
J 0
(-1775 4175);
DISPLAY INVISIBLE (-1775 4175);
FORCEPROP 1 LAST PATH I374
J 0
(-1825 4325);
DISPLAY 0.978723 (-1825 4325);
PAINT WHITE (-1825 4325);
DISPLAY INVISIBLE (-1825 4325);
FORCEPROP 1 LAST WATTAGE 1/16W
J 2
(-1800 4025);
DISPLAY 0.510638 (-1800 4025);
PAINT SKYBLUE (-1800 4025);
DISPLAY INVISIBLE (-1800 4025);
FORCEPROP 1 LAST PART_NUMBER CS03322FB03
J 0
(-1825 4275);
DISPLAY 0.510638 (-1825 4275);
PAINT WHITE (-1825 4275);
DISPLAY INVISIBLE (-1825 4275);
FORCEPROP 1 LAST TOLERANCE 1%
J 0
(-1650 4175);
DISPLAY 0.510638 (-1650 4175);
PAINT SKYBLUE (-1650 4175);
DISPLAY INVISIBLE (-1650 4175);
FORCEPROP 1 LAST $LOCATION R401
J 0
(-2050 4175);
DISPLAY 0.702128 (-2050 4175);
PAINT YELLOW (-2050 4175);
FORCEPROP 1 LASTPIN (-1875 4175) $PN 1
J 0
(-1863 4187);
DISPLAY 0.787234 (-1863 4187);
PAINT MONO (-1863 4187);
FORCEPROP 1 LASTPIN (-1675 4175) $PN 2
J 0
(-1713 4187);
DISPLAY 0.787234 (-1713 4187);
PAINT MONO (-1713 4187);
FORCEPROP 0 LAST CDS_LOCATION R401
J 0
(-2050 4225);
DISPLAY 0.680851 (-2050 4225);
DISPLAY INVISIBLE (-2050 4225);
FORCEPROP 0 LAST $SEC 1
J 0
(-2050 4225);
DISPLAY 0.680851 (-2050 4225);
PAINT MONO (-2050 4225);
DISPLAY INVISIBLE (-2050 4225);
FORCEPROP 0 LAST CDS_SEC 1
J 0
(-2050 4225);
DISPLAY 0.680851 (-2050 4225);
DISPLAY INVISIBLE (-2050 4225);
FORCEADD Q_RES..1
(3275 1375);
FORCEPROP 1 LAST VALUE 33.2
J 0
(3375 1375);
DISPLAY 0.510638 (3375 1375);
PAINT SKYBLUE (3375 1375);
FORCEPROP 1 LAST MATERIAL CHIP
J 0
(3500 1375);
DISPLAY 0.510638 (3500 1375);
PAINT SKYBLUE (3500 1375);
FORCEPROP 1 LAST PATH I381
J 0
(3225 1525);
DISPLAY 0.978723 (3225 1525);
PAINT WHITE (3225 1525);
DISPLAY INVISIBLE (3225 1525);
FORCEPROP 1 LAST PACK_TYPE 0402LF
J 0
(3525 1225);
DISPLAY 0.510638 (3525 1225);
PAINT SKYBLUE (3525 1225);
DISPLAY INVISIBLE (3525 1225);
FORCEPROP 1 LAST WATTAGE 1/16W
J 2
(3250 1225);
DISPLAY 0.510638 (3250 1225);
PAINT SKYBLUE (3250 1225);
DISPLAY INVISIBLE (3250 1225);
FORCEPROP 2 LAST CDS_LIB pure_quanta
J 0
(3275 1375);
DISPLAY INVISIBLE (3275 1375);
FORCEPROP 1 LAST PART_NUMBER CS03322FB03
J 0
(3225 1475);
DISPLAY 0.510638 (3225 1475);
PAINT WHITE (3225 1475);
DISPLAY INVISIBLE (3225 1475);
FORCEPROP 1 LAST TOLERANCE 1%
J 0
(3400 1375);
DISPLAY 0.510638 (3400 1375);
PAINT SKYBLUE (3400 1375);
DISPLAY INVISIBLE (3400 1375);
FORCEPROP 1 LAST LOCATION R121
J 0
(3050 1375);
DISPLAY 0.702128 (3050 1375);
PAINT YELLOW (3050 1375);
FORCEPROP 1 LASTPIN (3175 1375) $PN 1
J 0
(3187 1387);
DISPLAY 0.808511 (3187 1387);
PAINT WHITE (3187 1387);
FORCEPROP 1 LASTPIN (3375 1375) $PN 2
J 0
(3337 1387);
DISPLAY 0.808511 (3337 1387);
PAINT WHITE (3337 1387);
FORCEPROP 0 LAST $SEC 1
J 0
(3225 1475);
DISPLAY 0.680851 (3225 1475);
PAINT MONO (3225 1475);
DISPLAY INVISIBLE (3225 1475);
FORCEPROP 0 LAST CDS_SEC 1
J 0
(3225 1475);
DISPLAY 0.680851 (3225 1475);
DISPLAY INVISIBLE (3225 1475);
FORCEADD Q_RES..1
(3275 1225);
FORCEPROP 1 LAST VALUE 33.2
J 0
(3375 1225);
DISPLAY 0.510638 (3375 1225);
PAINT SKYBLUE (3375 1225);
FORCEPROP 1 LAST MATERIAL CHIP
J 0
(3500 1225);
DISPLAY 0.510638 (3500 1225);
PAINT SKYBLUE (3500 1225);
FORCEPROP 1 LAST PATH I382
J 0
(3225 1375);
DISPLAY 0.978723 (3225 1375);
PAINT WHITE (3225 1375);
DISPLAY INVISIBLE (3225 1375);
FORCEPROP 1 LAST PACK_TYPE 0402LF
J 0
(3525 1075);
DISPLAY 0.510638 (3525 1075);
PAINT SKYBLUE (3525 1075);
DISPLAY INVISIBLE (3525 1075);
FORCEPROP 1 LAST WATTAGE 1/16W
J 2
(3250 1075);
DISPLAY 0.510638 (3250 1075);
PAINT SKYBLUE (3250 1075);
DISPLAY INVISIBLE (3250 1075);
FORCEPROP 2 LAST CDS_LIB pure_quanta
J 0
(3275 1225);
DISPLAY INVISIBLE (3275 1225);
FORCEPROP 1 LAST PART_NUMBER CS03322FB03
J 0
(3225 1325);
DISPLAY 0.510638 (3225 1325);
PAINT WHITE (3225 1325);
DISPLAY INVISIBLE (3225 1325);
FORCEPROP 1 LAST TOLERANCE 1%
J 0
(3400 1225);
DISPLAY 0.510638 (3400 1225);
PAINT SKYBLUE (3400 1225);
DISPLAY INVISIBLE (3400 1225);
FORCEPROP 1 LAST LOCATION R60
J 0
(3050 1225);
DISPLAY 0.702128 (3050 1225);
PAINT YELLOW (3050 1225);
FORCEPROP 1 LASTPIN (3175 1225) $PN 1
J 0
(3187 1237);
DISPLAY 0.808511 (3187 1237);
PAINT WHITE (3187 1237);
FORCEPROP 1 LASTPIN (3375 1225) $PN 2
J 0
(3337 1237);
DISPLAY 0.808511 (3337 1237);
PAINT WHITE (3337 1237);
FORCEPROP 2 LAST $SEC 1
J 0
(3225 1425);
DISPLAY 0.680851 (3225 1425);
PAINT MONO (3225 1425);
DISPLAY INVISIBLE (3225 1425);
FORCEPROP 0 LAST CDS_SEC 1
J 0
(3225 1425);
DISPLAY 0.680851 (3225 1425);
PAINT MONO (3225 1425);
DISPLAY INVISIBLE (3225 1425);
FORCEADD Q_RES..1
(3275 1275);
FORCEPROP 1 LAST VALUE 33.2
J 0
(3375 1275);
DISPLAY 0.510638 (3375 1275);
PAINT SKYBLUE (3375 1275);
FORCEPROP 1 LAST MATERIAL CHIP
J 0
(3500 1275);
DISPLAY 0.510638 (3500 1275);
PAINT SKYBLUE (3500 1275);
FORCEPROP 1 LAST TOLERANCE 1%
J 0
(3400 1275);
DISPLAY 0.510638 (3400 1275);
PAINT SKYBLUE (3400 1275);
DISPLAY INVISIBLE (3400 1275);
FORCEPROP 1 LAST PART_NUMBER CS03322FB03
J 0
(3225 1375);
DISPLAY 0.510638 (3225 1375);
PAINT WHITE (3225 1375);
DISPLAY INVISIBLE (3225 1375);
FORCEPROP 2 LAST CDS_LIB pure_quanta
J 0
(3275 1275);
DISPLAY INVISIBLE (3275 1275);
FORCEPROP 1 LAST WATTAGE 1/16W
J 2
(3250 1125);
DISPLAY 0.510638 (3250 1125);
PAINT SKYBLUE (3250 1125);
DISPLAY INVISIBLE (3250 1125);
FORCEPROP 1 LAST PACK_TYPE 0402LF
J 0
(3525 1125);
DISPLAY 0.510638 (3525 1125);
PAINT SKYBLUE (3525 1125);
DISPLAY INVISIBLE (3525 1125);
FORCEPROP 1 LAST PATH I383
J 0
(3225 1425);
DISPLAY 0.978723 (3225 1425);
PAINT WHITE (3225 1425);
DISPLAY INVISIBLE (3225 1425);
FORCEPROP 1 LAST LOCATION R688
J 0
(3050 1275);
DISPLAY 0.702128 (3050 1275);
PAINT YELLOW (3050 1275);
FORCEPROP 1 LASTPIN (3175 1275) $PN 1
J 0
(3187 1287);
DISPLAY 0.808511 (3187 1287);
PAINT WHITE (3187 1287);
FORCEPROP 1 LASTPIN (3375 1275) $PN 2
J 0
(3337 1287);
DISPLAY 0.808511 (3337 1287);
PAINT WHITE (3337 1287);
FORCEPROP 2 LAST $SEC 1
J 0
(3225 1475);
DISPLAY 0.680851 (3225 1475);
PAINT MONO (3225 1475);
DISPLAY INVISIBLE (3225 1475);
FORCEPROP 0 LAST CDS_SEC 1
J 0
(3225 1475);
DISPLAY 0.680851 (3225 1475);
PAINT MONO (3225 1475);
DISPLAY INVISIBLE (3225 1475);
FORCEADD Q_RES..1
(3275 1325);
FORCEPROP 1 LAST VALUE 33.2
J 0
(3375 1325);
DISPLAY 0.510638 (3375 1325);
PAINT SKYBLUE (3375 1325);
FORCEPROP 1 LAST MATERIAL CHIP
J 0
(3500 1325);
DISPLAY 0.510638 (3500 1325);
PAINT SKYBLUE (3500 1325);
FORCEPROP 1 LAST PATH I384
J 0
(3225 1475);
DISPLAY 0.978723 (3225 1475);
PAINT WHITE (3225 1475);
DISPLAY INVISIBLE (3225 1475);
FORCEPROP 1 LAST PACK_TYPE 0402LF
J 0
(3525 1175);
DISPLAY 0.510638 (3525 1175);
PAINT SKYBLUE (3525 1175);
DISPLAY INVISIBLE (3525 1175);
FORCEPROP 1 LAST WATTAGE 1/16W
J 2
(3250 1175);
DISPLAY 0.510638 (3250 1175);
PAINT SKYBLUE (3250 1175);
DISPLAY INVISIBLE (3250 1175);
FORCEPROP 2 LAST CDS_LIB pure_quanta
J 0
(3275 1325);
DISPLAY INVISIBLE (3275 1325);
FORCEPROP 1 LAST PART_NUMBER CS03322FB03
J 0
(3225 1425);
DISPLAY 0.510638 (3225 1425);
PAINT WHITE (3225 1425);
DISPLAY INVISIBLE (3225 1425);
FORCEPROP 1 LAST TOLERANCE 1%
J 0
(3400 1325);
DISPLAY 0.510638 (3400 1325);
PAINT SKYBLUE (3400 1325);
DISPLAY INVISIBLE (3400 1325);
FORCEPROP 1 LAST LOCATION R242
J 0
(3050 1325);
DISPLAY 0.702128 (3050 1325);
PAINT YELLOW (3050 1325);
FORCEPROP 1 LASTPIN (3175 1325) $PN 1
J 0
(3187 1337);
DISPLAY 0.808511 (3187 1337);
PAINT WHITE (3187 1337);
FORCEPROP 1 LASTPIN (3375 1325) $PN 2
J 0
(3337 1337);
DISPLAY 0.808511 (3337 1337);
PAINT WHITE (3337 1337);
FORCEPROP 2 LAST $SEC 1
J 0
(3225 1525);
DISPLAY 0.680851 (3225 1525);
PAINT MONO (3225 1525);
DISPLAY INVISIBLE (3225 1525);
FORCEPROP 0 LAST CDS_SEC 1
J 0
(3225 1525);
DISPLAY 0.680851 (3225 1525);
PAINT MONO (3225 1525);
DISPLAY INVISIBLE (3225 1525);
FORCEADD OFFPAGE..4
(4950 1425);
FORCEPROP 2 LAST $XR0 12 
J 0
(5136 1425);
DISPLAY 0.638298 (5136 1425);
PAINT MONO (5136 1425);
FORCEPROP 2 LAST CDS_LIB standard
J 0
(4950 1425);
DISPLAY INVISIBLE (4950 1425);
FORCEPROP 2 LAST PATH I392
J 0
(5125 1500);
DISPLAY 0.680851 (5125 1500);
DISPLAY INVISIBLE (5125 1500);
FORCEPROP 1 LAST COMMENT_BODY TRUE
J 0
(4925 1325);
DISPLAY 1.574468 (4925 1325);
PAINT PEACH (4925 1325);
DISPLAY INVISIBLE (4925 1325);
FORCEPROP 1 LAST OFFPAGE TRUE
J 0
(5275 1300);
DISPLAY 1.574468 (5275 1300);
PAINT GREEN (5275 1300);
DISPLAY INVISIBLE (5275 1300);
FORCEADD OFFPAGE..4
(4950 1375);
FORCEPROP 2 LAST $XR0 11 
J 0
(5136 1375);
DISPLAY 0.638298 (5136 1375);
PAINT MONO (5136 1375);
FORCEPROP 2 LAST $XR1 34 
J 0
(5226 1375);
DISPLAY 0.638298 (5226 1375);
PAINT MONO (5226 1375);
FORCEPROP 2 LAST $XR2 28 
J 0
(5316 1375);
DISPLAY 0.638298 (5316 1375);
PAINT MONO (5316 1375);
FORCEPROP 2 LAST CDS_LIB standard
J 0
(4950 1375);
DISPLAY INVISIBLE (4950 1375);
FORCEPROP 2 LAST PATH I393
J 0
(5125 1450);
DISPLAY 0.680851 (5125 1450);
DISPLAY INVISIBLE (5125 1450);
FORCEPROP 1 LAST OFFPAGE TRUE
J 0
(5275 1250);
DISPLAY 1.574468 (5275 1250);
PAINT GREEN (5275 1250);
DISPLAY INVISIBLE (5275 1250);
FORCEPROP 1 LAST COMMENT_BODY TRUE
J 0
(4925 1275);
DISPLAY 1.574468 (4925 1275);
PAINT PEACH (4925 1275);
DISPLAY INVISIBLE (4925 1275);
FORCEADD OFFPAGE..2
(4950 1325);
FORCEPROP 2 LAST $XR0 36 
J 0
(5139 1325);
DISPLAY 0.638298 (5139 1325);
PAINT MONO (5139 1325);
FORCEPROP 2 LAST CDS_LIB standard
J 0
(4950 1325);
DISPLAY INVISIBLE (4950 1325);
FORCEPROP 2 LAST PATH I394
J 0
(5125 1400);
DISPLAY 0.680851 (5125 1400);
DISPLAY INVISIBLE (5125 1400);
FORCEPROP 1 LAST COMMENT_BODY TRUE
J 0
(4905 1230);
DISPLAY 0.872340 (4905 1230);
PAINT PEACH (4905 1230);
DISPLAY INVISIBLE (4905 1230);
FORCEPROP 1 LAST OFFPAGE TRUE
J 0
(5275 1200);
DISPLAY 0.872340 (5275 1200);
PAINT GREEN (5275 1200);
DISPLAY INVISIBLE (5275 1200);
FORCEADD OFFPAGE..2
(4950 1275);
FORCEPROP 2 LAST $XR2 35 
J 0
(5139 1239);
DISPLAY 0.638298 (5139 1239);
PAINT MONO (5139 1239);
FORCEPROP 2 LAST $XR1 10 
J 0
(5229 1275);
DISPLAY 0.638298 (5229 1275);
PAINT MONO (5229 1275);
FORCEPROP 2 LAST $XR0 11 
J 0
(5139 1275);
DISPLAY 0.638298 (5139 1275);
PAINT MONO (5139 1275);
FORCEPROP 2 LAST CDS_LIB standard
J 0
(4950 1275);
DISPLAY INVISIBLE (4950 1275);
FORCEPROP 2 LAST PATH I395
J 0
(5125 1350);
DISPLAY 0.680851 (5125 1350);
DISPLAY INVISIBLE (5125 1350);
FORCEPROP 1 LAST OFFPAGE TRUE
J 0
(5275 1150);
DISPLAY 0.872340 (5275 1150);
PAINT GREEN (5275 1150);
DISPLAY INVISIBLE (5275 1150);
FORCEPROP 1 LAST COMMENT_BODY TRUE
J 0
(4905 1180);
DISPLAY 0.872340 (4905 1180);
PAINT PEACH (4905 1180);
DISPLAY INVISIBLE (4905 1180);
FORCEADD OFFPAGE..2
(4950 1225);
FORCEPROP 2 LAST $XR1 10 
J 0
(5199 1189);
DISPLAY 0.638298 (5199 1189);
PAINT MONO (5199 1189);
FORCEPROP 2 LAST $XR0 11 
J 0
(5199 1225);
DISPLAY 0.638298 (5199 1225);
PAINT MONO (5199 1225);
FORCEPROP 2 LAST $XR3 36 
J 0
(5199 1117);
DISPLAY 0.638298 (5199 1117);
PAINT MONO (5199 1117);
FORCEPROP 2 LAST $XR2 35 
J 0
(5199 1153);
DISPLAY 0.638298 (5199 1153);
PAINT MONO (5199 1153);
FORCEPROP 2 LAST CDS_LIB standard
J 0
(4950 1225);
DISPLAY INVISIBLE (4950 1225);
FORCEPROP 2 LAST PATH I396
J 0
(5125 1300);
DISPLAY 0.680851 (5125 1300);
DISPLAY INVISIBLE (5125 1300);
FORCEPROP 1 LAST OFFPAGE TRUE
J 0
(5275 1100);
DISPLAY 0.872340 (5275 1100);
PAINT GREEN (5275 1100);
DISPLAY INVISIBLE (5275 1100);
FORCEPROP 1 LAST COMMENT_BODY TRUE
J 0
(4905 1130);
DISPLAY 0.872340 (4905 1130);
PAINT PEACH (4905 1130);
DISPLAY INVISIBLE (4905 1130);
FORCEADD Q_RES..1
(-2175 1375);
FORCEPROP 1 LAST VALUE 33.2
J 0
(-2075 1375);
DISPLAY 0.510638 (-2075 1375);
PAINT SKYBLUE (-2075 1375);
FORCEPROP 1 LAST MATERIAL EMPTY
J 0
(-1950 1375);
DISPLAY 0.510638 (-1950 1375);
PAINT RED (-1950 1375);
FORCEPROP 1 LAST TOLERANCE 1%
J 0
(-2050 1375);
DISPLAY 0.510638 (-2050 1375);
PAINT SKYBLUE (-2050 1375);
DISPLAY INVISIBLE (-2050 1375);
FORCEPROP 1 LAST PART_NUMBER CS03322FB03
J 0
(-2225 1475);
DISPLAY 0.510638 (-2225 1475);
PAINT WHITE (-2225 1475);
DISPLAY INVISIBLE (-2225 1475);
FORCEPROP 2 LAST CDS_LIB pure_quanta
J 0
(-2175 1375);
DISPLAY INVISIBLE (-2175 1375);
FORCEPROP 1 LAST WATTAGE 1/16W
J 2
(-2200 1225);
DISPLAY 0.510638 (-2200 1225);
PAINT SKYBLUE (-2200 1225);
DISPLAY INVISIBLE (-2200 1225);
FORCEPROP 1 LAST PACK_TYPE 0402LF
J 0
(-1925 1225);
DISPLAY 0.510638 (-1925 1225);
PAINT SKYBLUE (-1925 1225);
DISPLAY INVISIBLE (-1925 1225);
FORCEPROP 1 LAST PATH I398
J 0
(-2225 1525);
DISPLAY 0.978723 (-2225 1525);
PAINT WHITE (-2225 1525);
DISPLAY INVISIBLE (-2225 1525);
FORCEPROP 1 LAST LOCATION R689
J 0
(-2350 1375);
DISPLAY 0.702128 (-2350 1375);
PAINT YELLOW (-2350 1375);
FORCEPROP 1 LASTPIN (-2275 1375) $PN 1
J 0
(-2263 1387);
DISPLAY 0.808511 (-2263 1387);
PAINT WHITE (-2263 1387);
FORCEPROP 1 LASTPIN (-2075 1375) $PN 2
J 0
(-2113 1387);
DISPLAY 0.808511 (-2113 1387);
PAINT WHITE (-2113 1387);
FORCEPROP 2 LAST $SEC 1
J 0
(-2225 1575);
DISPLAY 0.680851 (-2225 1575);
PAINT MONO (-2225 1575);
DISPLAY INVISIBLE (-2225 1575);
FORCEPROP 0 LAST CDS_SEC 1
J 0
(-2225 1575);
DISPLAY 0.680851 (-2225 1575);
PAINT MONO (-2225 1575);
DISPLAY INVISIBLE (-2225 1575);
FORCEADD Q_RES..1
(-2200 1225);
FORCEPROP 1 LAST MATERIAL CHIP
J 0
(-2000 1225);
DISPLAY 0.510638 (-2000 1225);
PAINT SKYBLUE (-2000 1225);
FORCEPROP 1 LAST VALUE 33.2
J 0
(-2100 1225);
DISPLAY 0.510638 (-2100 1225);
PAINT SKYBLUE (-2100 1225);
FORCEPROP 1 LAST TOLERANCE 1%
J 0
(-2075 1225);
DISPLAY 0.510638 (-2075 1225);
PAINT SKYBLUE (-2075 1225);
DISPLAY INVISIBLE (-2075 1225);
FORCEPROP 1 LAST PART_NUMBER CS03322FB03
J 0
(-2250 1325);
DISPLAY 0.510638 (-2250 1325);
PAINT WHITE (-2250 1325);
DISPLAY INVISIBLE (-2250 1325);
FORCEPROP 2 LAST CDS_LIB pure_quanta
J 0
(-2200 1225);
DISPLAY INVISIBLE (-2200 1225);
FORCEPROP 1 LAST WATTAGE 1/16W
J 2
(-2225 1075);
DISPLAY 0.510638 (-2225 1075);
PAINT SKYBLUE (-2225 1075);
DISPLAY INVISIBLE (-2225 1075);
FORCEPROP 1 LAST PACK_TYPE 0402LF
J 0
(-1950 1075);
DISPLAY 0.510638 (-1950 1075);
PAINT SKYBLUE (-1950 1075);
DISPLAY INVISIBLE (-1950 1075);
FORCEPROP 1 LAST PATH I399
J 0
(-2250 1375);
DISPLAY 0.978723 (-2250 1375);
PAINT WHITE (-2250 1375);
DISPLAY INVISIBLE (-2250 1375);
FORCEPROP 1 LAST LOCATION R122
J 0
(-2425 1225);
DISPLAY 0.702128 (-2425 1225);
PAINT YELLOW (-2425 1225);
FORCEPROP 1 LASTPIN (-2300 1225) $PN 1
J 0
(-2288 1237);
DISPLAY 0.808511 (-2288 1237);
PAINT WHITE (-2288 1237);
FORCEPROP 1 LASTPIN (-2100 1225) $PN 2
J 0
(-2138 1237);
DISPLAY 0.808511 (-2138 1237);
PAINT WHITE (-2138 1237);
FORCEPROP 0 LAST $SEC 1
J 0
(-2250 1325);
DISPLAY 0.680851 (-2250 1325);
PAINT MONO (-2250 1325);
DISPLAY INVISIBLE (-2250 1325);
FORCEPROP 0 LAST CDS_SEC 1
J 0
(-2250 1325);
DISPLAY 0.680851 (-2250 1325);
DISPLAY INVISIBLE (-2250 1325);
FORCEADD Q_RES..1
(-2800 -300);
FORCEPROP 1 LAST MATERIAL EMPTY
J 0
(-2525 -300);
DISPLAY 0.510638 (-2525 -300);
PAINT RED (-2525 -300);
FORCEPROP 1 LAST VALUE 0
J 2
(-2600 -300);
DISPLAY 0.510638 (-2600 -300);
PAINT SKYBLUE (-2600 -300);
FORCEPROP 1 LAST PART_NUMBER CS00002JB13
J 0
(-2800 -125);
DISPLAY 0.510638 (-2800 -125);
PAINT WHITE (-2800 -125);
DISPLAY INVISIBLE (-2800 -125);
FORCEPROP 1 LAST PACK_TYPE 0402LF
J 0
(-2600 -200);
DISPLAY 0.510638 (-2600 -200);
PAINT SKYBLUE (-2600 -200);
DISPLAY INVISIBLE (-2600 -200);
FORCEPROP 1 LAST WATTAGE 1/16W
J 2
(-2625 -200);
DISPLAY 0.510638 (-2625 -200);
PAINT SKYBLUE (-2625 -200);
DISPLAY INVISIBLE (-2625 -200);
FORCEPROP 1 LAST PATH I4
J 0
(-2850 -150);
DISPLAY 0.978723 (-2850 -150);
PAINT WHITE (-2850 -150);
DISPLAY INVISIBLE (-2850 -150);
FORCEPROP 1 LAST TOLERANCE 5%
J 0
(-2300 -200);
DISPLAY 0.510638 (-2300 -200);
PAINT SKYBLUE (-2300 -200);
DISPLAY INVISIBLE (-2300 -200);
FORCEPROP 2 LAST CDS_LIB pure_quanta
J 0
(-2800 -300);
DISPLAY INVISIBLE (-2800 -300);
FORCEPROP 1 LAST LOCATION R156
J 0
(-3150 -300);
DISPLAY 0.702128 (-3150 -300);
PAINT YELLOW (-3150 -300);
FORCEPROP 1 LASTPIN (-2900 -300) $PN 1
J 0
(-2888 -288);
DISPLAY 0.808511 (-2888 -288);
PAINT WHITE (-2888 -288);
FORCEPROP 1 LASTPIN (-2700 -300) $PN 2
J 0
(-2738 -288);
DISPLAY 0.808511 (-2738 -288);
PAINT WHITE (-2738 -288);
FORCEPROP 0 LAST $SEC 1
J 0
(-2850 -200);
DISPLAY 0.680851 (-2850 -200);
PAINT MONO (-2850 -200);
DISPLAY INVISIBLE (-2850 -200);
FORCEPROP 0 LAST CDS_SEC 1
J 0
(-2850 -200);
DISPLAY 0.680851 (-2850 -200);
DISPLAY INVISIBLE (-2850 -200);
FORCEADD Q_RES..1
(-2200 1175);
FORCEPROP 1 LAST MATERIAL CHIP
J 0
(-2000 1175);
DISPLAY 0.510638 (-2000 1175);
PAINT SKYBLUE (-2000 1175);
FORCEPROP 1 LAST VALUE 33.2
J 0
(-2100 1175);
DISPLAY 0.510638 (-2100 1175);
PAINT SKYBLUE (-2100 1175);
FORCEPROP 1 LAST PACK_TYPE 0402LF
J 0
(-1950 1025);
DISPLAY 0.510638 (-1950 1025);
PAINT SKYBLUE (-1950 1025);
DISPLAY INVISIBLE (-1950 1025);
FORCEPROP 1 LAST WATTAGE 1/16W
J 2
(-2225 1025);
DISPLAY 0.510638 (-2225 1025);
PAINT SKYBLUE (-2225 1025);
DISPLAY INVISIBLE (-2225 1025);
FORCEPROP 2 LAST CDS_LIB pure_quanta
J 0
(-2200 1175);
DISPLAY INVISIBLE (-2200 1175);
FORCEPROP 1 LAST PART_NUMBER CS03322FB03
J 0
(-2250 1275);
DISPLAY 0.510638 (-2250 1275);
PAINT WHITE (-2250 1275);
DISPLAY INVISIBLE (-2250 1275);
FORCEPROP 1 LAST TOLERANCE 1%
J 0
(-2075 1175);
DISPLAY 0.510638 (-2075 1175);
PAINT SKYBLUE (-2075 1175);
DISPLAY INVISIBLE (-2075 1175);
FORCEPROP 1 LAST PATH I400
J 0
(-2250 1325);
DISPLAY 0.978723 (-2250 1325);
PAINT WHITE (-2250 1325);
DISPLAY INVISIBLE (-2250 1325);
FORCEPROP 1 LAST LOCATION R760
J 0
(-2425 1175);
DISPLAY 0.702128 (-2425 1175);
PAINT YELLOW (-2425 1175);
FORCEPROP 1 LASTPIN (-2300 1175) $PN 1
J 0
(-2288 1187);
DISPLAY 0.808511 (-2288 1187);
PAINT WHITE (-2288 1187);
FORCEPROP 1 LASTPIN (-2100 1175) $PN 2
J 0
(-2138 1187);
DISPLAY 0.808511 (-2138 1187);
PAINT WHITE (-2138 1187);
FORCEPROP 0 LAST $SEC 1
J 0
(-2250 1275);
DISPLAY 0.680851 (-2250 1275);
PAINT MONO (-2250 1275);
DISPLAY INVISIBLE (-2250 1275);
FORCEPROP 0 LAST CDS_SEC 1
J 0
(-2250 1275);
DISPLAY 0.680851 (-2250 1275);
DISPLAY INVISIBLE (-2250 1275);
FORCEADD Q_RES..1
(-2200 1775);
FORCEPROP 1 LAST VALUE 33.2
J 0
(-2100 1775);
DISPLAY 0.510638 (-2100 1775);
PAINT SKYBLUE (-2100 1775);
FORCEPROP 1 LAST MATERIAL CHIP
J 0
(-2000 1775);
DISPLAY 0.510638 (-2000 1775);
PAINT SKYBLUE (-2000 1775);
FORCEPROP 1 LAST PATH I402
J 0
(-2250 1925);
DISPLAY 0.978723 (-2250 1925);
PAINT WHITE (-2250 1925);
DISPLAY INVISIBLE (-2250 1925);
FORCEPROP 1 LAST TOLERANCE 1%
J 0
(-2075 1775);
DISPLAY 0.510638 (-2075 1775);
PAINT SKYBLUE (-2075 1775);
DISPLAY INVISIBLE (-2075 1775);
FORCEPROP 1 LAST PART_NUMBER CS03322FB03
J 0
(-2250 1875);
DISPLAY 0.510638 (-2250 1875);
PAINT WHITE (-2250 1875);
DISPLAY INVISIBLE (-2250 1875);
FORCEPROP 2 LAST CDS_LIB pure_quanta
J 0
(-2200 1775);
DISPLAY INVISIBLE (-2200 1775);
FORCEPROP 1 LAST WATTAGE 1/16W
J 2
(-2225 1625);
DISPLAY 0.510638 (-2225 1625);
PAINT SKYBLUE (-2225 1625);
DISPLAY INVISIBLE (-2225 1625);
FORCEPROP 1 LAST PACK_TYPE 0402LF
J 0
(-1950 1625);
DISPLAY 0.510638 (-1950 1625);
PAINT SKYBLUE (-1950 1625);
DISPLAY INVISIBLE (-1950 1625);
FORCEPROP 1 LAST LOCATION R763
J 0
(-2425 1775);
DISPLAY 0.702128 (-2425 1775);
PAINT YELLOW (-2425 1775);
FORCEPROP 1 LASTPIN (-2300 1775) $PN 1
J 0
(-2288 1787);
DISPLAY 0.808511 (-2288 1787);
PAINT WHITE (-2288 1787);
FORCEPROP 1 LASTPIN (-2100 1775) $PN 2
J 0
(-2138 1787);
DISPLAY 0.808511 (-2138 1787);
PAINT WHITE (-2138 1787);
FORCEPROP 0 LAST $SEC 1
J 0
(-2425 1825);
DISPLAY 0.680851 (-2425 1825);
PAINT MONO (-2425 1825);
DISPLAY INVISIBLE (-2425 1825);
FORCEPROP 0 LAST CDS_SEC 1
J 0
(-2425 1825);
DISPLAY 0.680851 (-2425 1825);
DISPLAY INVISIBLE (-2425 1825);
FORCEADD OFFPAGE..5
(-3425 1225);
FORCEPROP 2 LAST $XR0 31 
J 0
(-3649 1225);
DISPLAY 0.638298 (-3649 1225);
PAINT MONO (-3649 1225);
FORCEPROP 2 LAST CDS_LIB standard
J 0
(-3425 1225);
DISPLAY INVISIBLE (-3425 1225);
FORCEPROP 1 LAST OFFPAGE TRUE
J 0
(-3100 1100);
DISPLAY 0.872340 (-3100 1100);
DISPLAY INVISIBLE (-3100 1100);
FORCEPROP 1 LAST COMMENT_BODY TRUE
J 0
(-3325 1150);
DISPLAY 0.872340 (-3325 1150);
PAINT GREEN (-3325 1150);
DISPLAY INVISIBLE (-3325 1150);
FORCEPROP 2 LAST PATH I403
J 0
(-3675 1275);
DISPLAY 0.680851 (-3675 1275);
DISPLAY INVISIBLE (-3675 1275);
FORCEADD OFFPAGE..5
(-3425 1175);
FORCEPROP 2 LAST $XR1 36 
J 0
(-3739 1175);
DISPLAY 0.638298 (-3739 1175);
PAINT MONO (-3739 1175);
FORCEPROP 2 LAST $XR0 42 
J 0
(-3649 1175);
DISPLAY 0.638298 (-3649 1175);
PAINT MONO (-3649 1175);
FORCEPROP 1 LAST COMMENT_BODY TRUE
J 0
(-3325 1100);
DISPLAY 0.872340 (-3325 1100);
PAINT GREEN (-3325 1100);
DISPLAY INVISIBLE (-3325 1100);
FORCEPROP 1 LAST OFFPAGE TRUE
J 0
(-3100 1050);
DISPLAY 0.872340 (-3100 1050);
DISPLAY INVISIBLE (-3100 1050);
FORCEPROP 2 LAST CDS_LIB standard
J 0
(-3425 1175);
DISPLAY INVISIBLE (-3425 1175);
FORCEPROP 2 LAST PATH I404
J 0
(-3675 1225);
DISPLAY 0.680851 (-3675 1225);
DISPLAY INVISIBLE (-3675 1225);
FORCEADD OFFPAGE..1
(-3425 1375);
FORCEPROP 2 LAST $XR2 35 
J 0
(-3826 1375);
DISPLAY 0.638298 (-3826 1375);
PAINT MONO (-3826 1375);
FORCEPROP 2 LAST $XR1 11 
J 0
(-3736 1375);
DISPLAY 0.638298 (-3736 1375);
PAINT MONO (-3736 1375);
FORCEPROP 2 LAST $XR0 10 
J 0
(-3646 1375);
DISPLAY 0.638298 (-3646 1375);
PAINT MONO (-3646 1375);
FORCEPROP 2 LAST PATH I405
J 0
(-3675 1425);
DISPLAY 0.680851 (-3675 1425);
DISPLAY INVISIBLE (-3675 1425);
FORCEPROP 1 LAST COMMENT_BODY TRUE
J 0
(-3300 1275);
DISPLAY 0.872340 (-3300 1275);
PAINT PEACH (-3300 1275);
DISPLAY INVISIBLE (-3300 1275);
FORCEPROP 1 LAST OFFPAGE TRUE
J 0
(-3100 1250);
DISPLAY 0.872340 (-3100 1250);
PAINT GREEN (-3100 1250);
DISPLAY INVISIBLE (-3100 1250);
FORCEPROP 2 LAST CDS_LIB standard
J 0
(-3425 1375);
DISPLAY INVISIBLE (-3425 1375);
FORCEADD OFFPAGE..4
R 2
(-3425 1775);
FORCEPROP 2 LAST $XR0 12 
J 0
(-3646 1775);
DISPLAY 0.638298 (-3646 1775);
PAINT MONO (-3646 1775);
FORCEPROP 2 LAST $XR1 34 
J 0
(-3736 1775);
DISPLAY 0.638298 (-3736 1775);
PAINT MONO (-3736 1775);
FORCEPROP 2 LAST PATH I406
J 0
(-3625 1825);
DISPLAY 0.680851 (-3625 1825);
DISPLAY INVISIBLE (-3625 1825);
FORCEPROP 2 LAST CDS_LIB standard
J 0
(-3425 1775);
DISPLAY INVISIBLE (-3425 1775);
FORCEPROP 1 LAST OFFPAGE TRUE
J 2
(-3750 1650);
DISPLAY 0.872340 (-3750 1650);
PAINT GREEN (-3750 1650);
DISPLAY INVISIBLE (-3750 1650);
FORCEPROP 1 LAST COMMENT_BODY TRUE
J 2
(-3400 1675);
DISPLAY 0.872340 (-3400 1675);
PAINT PEACH (-3400 1675);
DISPLAY INVISIBLE (-3400 1675);
FORCEADD Q_RES..1
(3250 3875);
FORCEPROP 1 LAST VALUE 33.2
J 0
(3350 3875);
DISPLAY 0.510638 (3350 3875);
PAINT SKYBLUE (3350 3875);
FORCEPROP 1 LAST MATERIAL CHIP
J 0
(3450 3875);
DISPLAY 0.510638 (3450 3875);
PAINT SKYBLUE (3450 3875);
FORCEPROP 1 LAST PATH I407
J 0
(3200 4025);
DISPLAY 0.978723 (3200 4025);
PAINT WHITE (3200 4025);
DISPLAY INVISIBLE (3200 4025);
FORCEPROP 1 LAST PACK_TYPE 0402LF
J 0
(3500 3725);
DISPLAY 0.510638 (3500 3725);
PAINT SKYBLUE (3500 3725);
DISPLAY INVISIBLE (3500 3725);
FORCEPROP 1 LAST WATTAGE 1/16W
J 2
(3225 3725);
DISPLAY 0.510638 (3225 3725);
PAINT SKYBLUE (3225 3725);
DISPLAY INVISIBLE (3225 3725);
FORCEPROP 2 LAST CDS_LIB pure_quanta
J 0
(3250 3875);
DISPLAY INVISIBLE (3250 3875);
FORCEPROP 1 LAST PART_NUMBER CS03322FB03
J 0
(3200 3975);
DISPLAY 0.510638 (3200 3975);
PAINT WHITE (3200 3975);
DISPLAY INVISIBLE (3200 3975);
FORCEPROP 1 LAST TOLERANCE 1%
J 0
(3375 3875);
DISPLAY 0.510638 (3375 3875);
PAINT SKYBLUE (3375 3875);
DISPLAY INVISIBLE (3375 3875);
FORCEPROP 1 LAST LOCATION R458
J 0
(3050 3875);
DISPLAY 0.702128 (3050 3875);
PAINT YELLOW (3050 3875);
FORCEPROP 1 LASTPIN (3150 3875) $PN 1
J 0
(3162 3887);
DISPLAY 0.808511 (3162 3887);
PAINT WHITE (3162 3887);
FORCEPROP 1 LASTPIN (3350 3875) $PN 2
J 0
(3312 3887);
DISPLAY 0.808511 (3312 3887);
PAINT WHITE (3312 3887);
FORCEPROP 2 LAST $SEC 1
J 0
(3200 4075);
DISPLAY 0.680851 (3200 4075);
PAINT MONO (3200 4075);
DISPLAY INVISIBLE (3200 4075);
FORCEPROP 0 LAST CDS_SEC 1
J 0
(3200 4075);
DISPLAY 0.680851 (3200 4075);
PAINT MONO (3200 4075);
DISPLAY INVISIBLE (3200 4075);
FORCEADD OFFPAGE..4
(4475 3875);
FORCEPROP 2 LAST $XR0 29 
J 0
(4691 3875);
DISPLAY 0.638298 (4691 3875);
PAINT MONO (4691 3875);
FORCEPROP 2 LAST $XR1 36 
J 0
(4781 3875);
DISPLAY 0.638298 (4781 3875);
PAINT MONO (4781 3875);
FORCEPROP 2 LAST CDS_LIB standard
J 0
(4475 3875);
DISPLAY INVISIBLE (4475 3875);
FORCEPROP 2 LAST PATH I409
J 0
(4650 3950);
DISPLAY 0.680851 (4650 3950);
DISPLAY INVISIBLE (4650 3950);
FORCEPROP 1 LAST COMMENT_BODY TRUE
J 0
(4450 3775);
DISPLAY 0.872340 (4450 3775);
PAINT PEACH (4450 3775);
DISPLAY INVISIBLE (4450 3775);
FORCEPROP 1 LAST OFFPAGE TRUE
J 0
(4800 3750);
DISPLAY 0.872340 (4800 3750);
PAINT GREEN (4800 3750);
DISPLAY INVISIBLE (4800 3750);
FORCEADD OFFPAGE..2
(4475 3825);
FORCEPROP 2 LAST $XR0 36 
J 0
(4664 3825);
DISPLAY 0.638298 (4664 3825);
PAINT MONO (4664 3825);
FORCEPROP 2 LAST CDS_LIB standard
J 0
(4475 3825);
DISPLAY INVISIBLE (4475 3825);
FORCEPROP 2 LAST PATH I413
J 0
(4650 3900);
DISPLAY 0.680851 (4650 3900);
DISPLAY INVISIBLE (4650 3900);
FORCEPROP 1 LAST COMMENT_BODY TRUE
J 0
(4430 3730);
DISPLAY 0.872340 (4430 3730);
PAINT GREEN (4430 3730);
DISPLAY INVISIBLE (4430 3730);
FORCEPROP 1 LAST OFFPAGE TRUE
J 0
(4800 3700);
DISPLAY 0.872340 (4800 3700);
DISPLAY INVISIBLE (4800 3700);
FORCEADD OFFPAGE..2
(4450 1825);
FORCEPROP 2 LAST $XR0 36 
J 0
(4639 1825);
DISPLAY 0.638298 (4639 1825);
PAINT MONO (4639 1825);
FORCEPROP 1 LAST COMMENT_BODY TRUE
J 0
(4405 1730);
DISPLAY 0.872340 (4405 1730);
PAINT GREEN (4405 1730);
DISPLAY INVISIBLE (4405 1730);
FORCEPROP 1 LAST OFFPAGE TRUE
J 0
(4775 1700);
DISPLAY 0.872340 (4775 1700);
DISPLAY INVISIBLE (4775 1700);
FORCEPROP 2 LAST PATH I414
J 0
(4625 1900);
DISPLAY 0.680851 (4625 1900);
DISPLAY INVISIBLE (4625 1900);
FORCEPROP 2 LAST CDS_LIB standard
J 0
(4450 1825);
DISPLAY INVISIBLE (4450 1825);
FORCEADD OFFPAGE..2
(4475 1025);
FORCEPROP 2 LAST $XR0 36 
J 0
(4664 1025);
DISPLAY 0.638298 (4664 1025);
PAINT MONO (4664 1025);
FORCEPROP 1 LAST COMMENT_BODY TRUE
J 0
(4430 930);
DISPLAY 0.872340 (4430 930);
PAINT GREEN (4430 930);
DISPLAY INVISIBLE (4430 930);
FORCEPROP 1 LAST OFFPAGE TRUE
J 0
(4800 900);
DISPLAY 0.872340 (4800 900);
DISPLAY INVISIBLE (4800 900);
FORCEPROP 2 LAST PATH I415
J 0
(4650 1100);
DISPLAY 0.680851 (4650 1100);
DISPLAY INVISIBLE (4650 1100);
FORCEPROP 2 LAST CDS_LIB standard
J 0
(4475 1025);
DISPLAY INVISIBLE (4475 1025);
FORCEADD OFFPAGE..4
(4950 1175);
FORCEPROP 2 LAST $XR0 10 
J 0
(5136 1175);
DISPLAY 0.638298 (5136 1175);
PAINT MONO (5136 1175);
FORCEPROP 2 LAST PATH I417
J 0
(5175 1225);
DISPLAY 0.680851 (5175 1225);
DISPLAY INVISIBLE (5175 1225);
FORCEPROP 1 LAST COMMENT_BODY TRUE
J 0
(4925 1075);
DISPLAY 0.872340 (4925 1075);
PAINT GREEN (4925 1075);
DISPLAY INVISIBLE (4925 1075);
FORCEPROP 1 LAST OFFPAGE TRUE
J 0
(5275 1050);
DISPLAY 0.872340 (5275 1050);
DISPLAY INVISIBLE (5275 1050);
FORCEPROP 2 LAST CDS_LIB standard
J 0
(4950 1175);
DISPLAY INVISIBLE (4950 1175);
FORCEADD Q_RES..1
(3650 3275);
FORCEPROP 1 LAST VALUE 33.2
J 1
(3800 3275);
DISPLAY 0.510638 (3800 3275);
PAINT SKYBLUE (3800 3275);
FORCEPROP 1 LAST MATERIAL CHIP
J 1
(3900 3275);
DISPLAY 0.510638 (3900 3275);
PAINT SKYBLUE (3900 3275);
FORCEPROP 1 LAST PATH I419
J 0
(3600 3425);
DISPLAY 0.978723 (3600 3425);
PAINT WHITE (3600 3425);
DISPLAY INVISIBLE (3600 3425);
FORCEPROP 1 LAST TOLERANCE 1%
J 0
(3775 3275);
DISPLAY 0.510638 (3775 3275);
PAINT SKYBLUE (3775 3275);
DISPLAY INVISIBLE (3775 3275);
FORCEPROP 1 LAST PART_NUMBER CS03322FB03
J 0
(3850 3175);
DISPLAY 0.510638 (3850 3175);
PAINT WHITE (3850 3175);
DISPLAY INVISIBLE (3850 3175);
FORCEPROP 1 LAST PACK_TYPE 0402LF
J 0
(3900 3125);
DISPLAY 0.510638 (3900 3125);
PAINT SKYBLUE (3900 3125);
DISPLAY INVISIBLE (3900 3125);
FORCEPROP 1 LAST WATTAGE 1/16W
J 2
(3625 3125);
DISPLAY 0.510638 (3625 3125);
PAINT SKYBLUE (3625 3125);
DISPLAY INVISIBLE (3625 3125);
FORCEPROP 2 LAST CDS_LIB pure_quanta
J 0
(3650 3275);
DISPLAY INVISIBLE (3650 3275);
FORCEPROP 2 LAST SEC_TYPE 0402LF
J 0
(3600 3475);
DISPLAY 0.680851 (3600 3475);
DISPLAY INVISIBLE (3600 3475);
FORCEPROP 1 LAST LOCATION R70
J 2
(3550 3275);
DISPLAY 0.702128 (3550 3275);
PAINT YELLOW (3550 3275);
FORCEPROP 1 LASTPIN (3550 3275) $PN 1
J 0
(3562 3287);
DISPLAY 0.808511 (3562 3287);
PAINT WHITE (3562 3287);
FORCEPROP 1 LASTPIN (3750 3275) $PN 2
J 0
(3712 3287);
DISPLAY 0.808511 (3712 3287);
PAINT WHITE (3712 3287);
FORCEPROP 0 LAST SEC 1
J 0
(3600 3375);
DISPLAY 0.680851 (3600 3375);
PAINT MONO (3600 3375);
DISPLAY INVISIBLE (3600 3375);
FORCEADD OFFPAGE..2
(4925 3275);
FORCEPROP 2 LAST $XR1 34 
J 0
(5204 3275);
DISPLAY 0.638298 (5204 3275);
PAINT MONO (5204 3275);
FORCEPROP 2 LAST $XR0 11 
J 0
(5114 3275);
DISPLAY 0.638298 (5114 3275);
PAINT MONO (5114 3275);
FORCEPROP 1 LAST COMMENT_BODY TRUE
J 0
(4880 3180);
DISPLAY 0.872340 (4880 3180);
PAINT PEACH (4880 3180);
DISPLAY INVISIBLE (4880 3180);
FORCEPROP 1 LAST OFFPAGE TRUE
J 0
(5250 3150);
DISPLAY 0.872340 (5250 3150);
PAINT GREEN (5250 3150);
DISPLAY INVISIBLE (5250 3150);
FORCEPROP 2 LAST PATH I420
J 0
(5100 3350);
DISPLAY 0.680851 (5100 3350);
DISPLAY INVISIBLE (5100 3350);
FORCEPROP 2 LAST CDS_LIB standard
J 0
(4925 3275);
DISPLAY INVISIBLE (4925 3275);
FORCEADD Q_RES..1
(3650 3225);
FORCEPROP 1 LAST VALUE 33.2
J 1
(3800 3225);
DISPLAY 0.510638 (3800 3225);
PAINT SKYBLUE (3800 3225);
FORCEPROP 1 LAST MATERIAL CHIP
J 1
(3900 3225);
DISPLAY 0.510638 (3900 3225);
PAINT SKYBLUE (3900 3225);
FORCEPROP 2 LAST SEC_TYPE 0402LF
J 0
(3600 3425);
DISPLAY 0.680851 (3600 3425);
DISPLAY INVISIBLE (3600 3425);
FORCEPROP 2 LAST CDS_LIB pure_quanta
J 0
(3650 3225);
DISPLAY INVISIBLE (3650 3225);
FORCEPROP 1 LAST WATTAGE 1/16W
J 2
(3625 3075);
DISPLAY 0.510638 (3625 3075);
PAINT SKYBLUE (3625 3075);
DISPLAY INVISIBLE (3625 3075);
FORCEPROP 1 LAST PACK_TYPE 0402LF
J 0
(3900 3075);
DISPLAY 0.510638 (3900 3075);
PAINT SKYBLUE (3900 3075);
DISPLAY INVISIBLE (3900 3075);
FORCEPROP 1 LAST PART_NUMBER CS03322FB03
J 0
(3850 3125);
DISPLAY 0.510638 (3850 3125);
PAINT WHITE (3850 3125);
DISPLAY INVISIBLE (3850 3125);
FORCEPROP 1 LAST TOLERANCE 1%
J 0
(3775 3225);
DISPLAY 0.510638 (3775 3225);
PAINT SKYBLUE (3775 3225);
DISPLAY INVISIBLE (3775 3225);
FORCEPROP 1 LAST PATH I421
J 0
(3600 3375);
DISPLAY 0.978723 (3600 3375);
PAINT WHITE (3600 3375);
DISPLAY INVISIBLE (3600 3375);
FORCEPROP 1 LAST LOCATION R65
J 2
(3550 3225);
DISPLAY 0.702128 (3550 3225);
PAINT YELLOW (3550 3225);
FORCEPROP 1 LASTPIN (3550 3225) $PN 1
J 0
(3562 3237);
DISPLAY 0.808511 (3562 3237);
PAINT WHITE (3562 3237);
FORCEPROP 1 LASTPIN (3750 3225) $PN 2
J 0
(3712 3237);
DISPLAY 0.808511 (3712 3237);
PAINT WHITE (3712 3237);
FORCEPROP 0 LAST SEC 1
J 0
(3600 3325);
DISPLAY 0.680851 (3600 3325);
PAINT MONO (3600 3325);
DISPLAY INVISIBLE (3600 3325);
FORCEADD OFFPAGE..3
(4925 3225);
FORCEPROP 2 LAST $XR0 34 
J 0
(5139 3225);
DISPLAY 0.638298 (5139 3225);
PAINT MONO (5139 3225);
FORCEPROP 2 LAST $XR1 42 
J 0
(5139 3225);
DISPLAY 0.638298 (5139 3225);
PAINT MONO (5139 3225);
FORCEPROP 2 LAST $XR2 31 
J 0
(5139 3225);
DISPLAY 0.638298 (5139 3225);
PAINT MONO (5139 3225);
FORCEPROP 2 LAST CDS_LIB standard
J 0
(4925 3225);
DISPLAY INVISIBLE (4925 3225);
FORCEPROP 2 LAST PATH I422
J 0
(5125 3300);
DISPLAY 0.680851 (5125 3300);
DISPLAY INVISIBLE (5125 3300);
FORCEPROP 1 LAST COMMENT_BODY TRUE
J 0
(4875 3125);
DISPLAY 0.872340 (4875 3125);
PAINT PEACH (4875 3125);
DISPLAY INVISIBLE (4875 3125);
FORCEPROP 1 LAST OFFPAGE TRUE
J 0
(5250 3100);
DISPLAY 0.872340 (5250 3100);
PAINT GREEN (5250 3100);
DISPLAY INVISIBLE (5250 3100);
FORCEADD OFFPAGE..2
(4450 1575);
FORCEPROP 2 LAST $XR0 35 
J 0
(4639 1575);
DISPLAY 0.638298 (4639 1575);
PAINT MONO (4639 1575);
FORCEPROP 2 LAST CDS_LIB standard
J 0
(4450 1575);
DISPLAY INVISIBLE (4450 1575);
FORCEPROP 1 LAST OFFPAGE TRUE
J 0
(4775 1450);
DISPLAY 0.872340 (4775 1450);
PAINT GREEN (4775 1450);
DISPLAY INVISIBLE (4775 1450);
FORCEPROP 1 LAST COMMENT_BODY TRUE
J 0
(4405 1480);
DISPLAY 0.872340 (4405 1480);
PAINT PEACH (4405 1480);
DISPLAY INVISIBLE (4405 1480);
FORCEPROP 2 LAST PATH I426
J 0
(4650 1625);
DISPLAY 0.680851 (4650 1625);
DISPLAY INVISIBLE (4650 1625);
FORCEADD Q_RES..1
(3150 1575);
FORCEPROP 1 LAST VALUE 33.2
J 1
(3325 1575);
DISPLAY 0.510638 (3325 1575);
PAINT SKYBLUE (3325 1575);
FORCEPROP 1 LAST MATERIAL CHIP
J 1
(3450 1575);
DISPLAY 0.510638 (3450 1575);
PAINT SKYBLUE (3450 1575);
FORCEPROP 1 LAST PATH I427
J 0
(3100 1725);
DISPLAY 0.978723 (3100 1725);
PAINT WHITE (3100 1725);
DISPLAY INVISIBLE (3100 1725);
FORCEPROP 1 LAST TOLERANCE 1%
J 0
(3275 1575);
DISPLAY 0.510638 (3275 1575);
PAINT SKYBLUE (3275 1575);
DISPLAY INVISIBLE (3275 1575);
FORCEPROP 1 LAST PART_NUMBER CS03322FB03
J 0
(3100 1675);
DISPLAY 0.510638 (3100 1675);
PAINT WHITE (3100 1675);
DISPLAY INVISIBLE (3100 1675);
FORCEPROP 1 LAST PACK_TYPE 0402LF
J 0
(3400 1425);
DISPLAY 0.510638 (3400 1425);
PAINT SKYBLUE (3400 1425);
DISPLAY INVISIBLE (3400 1425);
FORCEPROP 1 LAST WATTAGE 1/16W
J 2
(3125 1425);
DISPLAY 0.510638 (3125 1425);
PAINT SKYBLUE (3125 1425);
DISPLAY INVISIBLE (3125 1425);
FORCEPROP 2 LAST CDS_LIB pure_quanta
J 0
(3150 1575);
DISPLAY INVISIBLE (3150 1575);
FORCEPROP 1 LAST LOCATION R112
J 2
(3050 1575);
DISPLAY 0.872340 (3050 1575);
PAINT YELLOW (3050 1575);
FORCEPROP 1 LASTPIN (3050 1575) $PN 1
J 0
(3062 1587);
DISPLAY 0.808511 (3062 1587);
PAINT WHITE (3062 1587);
FORCEPROP 1 LASTPIN (3250 1575) $PN 2
J 0
(3212 1587);
DISPLAY 0.808511 (3212 1587);
PAINT WHITE (3212 1587);
FORCEPROP 0 LAST $SEC 1
J 0
(3250 1625);
DISPLAY 0.680851 (3250 1625);
PAINT MONO (3250 1625);
DISPLAY INVISIBLE (3250 1625);
FORCEPROP 0 LAST CDS_SEC 1
J 0
(3250 1625);
DISPLAY 0.680851 (3250 1625);
DISPLAY INVISIBLE (3250 1625);
FORCEADD OFFPAGE..5
R 2
(3075 1500);
FORCEPROP 2 LAST $XR0 13 
J 0
(3264 1500);
DISPLAY 0.638298 (3264 1500);
PAINT MONO (3264 1500);
FORCEPROP 2 LAST CDS_LIB standard
J 0
(3075 1500);
DISPLAY INVISIBLE (3075 1500);
FORCEPROP 1 LAST OFFPAGE TRUE
J 2
(2750 1375);
DISPLAY 0.872340 (2750 1375);
PAINT GREEN (2750 1375);
DISPLAY INVISIBLE (2750 1375);
FORCEPROP 1 LAST COMMENT_BODY TRUE
J 2
(2975 1425);
DISPLAY 0.872340 (2975 1425);
PAINT PEACH (2975 1425);
DISPLAY INVISIBLE (2975 1425);
FORCEPROP 2 LAST PATH I428
J 0
(3275 1550);
DISPLAY 0.680851 (3275 1550);
DISPLAY INVISIBLE (3275 1550);
FORCEADD OFFPAGE..2
(4450 1625);
FORCEPROP 2 LAST $XR0 44 
J 0
(4639 1625);
DISPLAY 0.638298 (4639 1625);
PAINT MONO (4639 1625);
FORCEPROP 2 LAST PATH I429
J 0
(4650 1675);
DISPLAY 0.680851 (4650 1675);
DISPLAY INVISIBLE (4650 1675);
FORCEPROP 1 LAST COMMENT_BODY TRUE
J 0
(4405 1530);
DISPLAY 0.872340 (4405 1530);
PAINT PEACH (4405 1530);
DISPLAY INVISIBLE (4405 1530);
FORCEPROP 1 LAST OFFPAGE TRUE
J 0
(4775 1500);
DISPLAY 0.872340 (4775 1500);
PAINT GREEN (4775 1500);
DISPLAY INVISIBLE (4775 1500);
FORCEPROP 2 LAST CDS_LIB standard
J 0
(4450 1625);
DISPLAY INVISIBLE (4450 1625);
FORCEADD Q_RES..1
(3150 1625);
FORCEPROP 1 LAST MATERIAL CHIP
J 1
(3400 1625);
DISPLAY 0.510638 (3400 1625);
PAINT SKYBLUE (3400 1625);
FORCEPROP 1 LAST VALUE 33.2
J 1
(3300 1625);
DISPLAY 0.510638 (3300 1625);
PAINT SKYBLUE (3300 1625);
FORCEPROP 1 LAST PATH I430
J 0
(3100 1775);
DISPLAY 0.978723 (3100 1775);
PAINT WHITE (3100 1775);
DISPLAY INVISIBLE (3100 1775);
FORCEPROP 1 LAST TOLERANCE 1%
J 0
(3275 1625);
DISPLAY 0.510638 (3275 1625);
PAINT SKYBLUE (3275 1625);
DISPLAY INVISIBLE (3275 1625);
FORCEPROP 1 LAST PART_NUMBER CS03322FB03
J 0
(3100 1725);
DISPLAY 0.510638 (3100 1725);
PAINT WHITE (3100 1725);
DISPLAY INVISIBLE (3100 1725);
FORCEPROP 1 LAST PACK_TYPE 0402LF
J 0
(3400 1475);
DISPLAY 0.510638 (3400 1475);
PAINT SKYBLUE (3400 1475);
DISPLAY INVISIBLE (3400 1475);
FORCEPROP 1 LAST WATTAGE 1/16W
J 2
(3125 1475);
DISPLAY 0.510638 (3125 1475);
PAINT SKYBLUE (3125 1475);
DISPLAY INVISIBLE (3125 1475);
FORCEPROP 2 LAST CDS_LIB pure_quanta
J 0
(3150 1625);
DISPLAY INVISIBLE (3150 1625);
FORCEPROP 1 LAST LOCATION R405
J 2
(3050 1625);
DISPLAY 0.872340 (3050 1625);
PAINT YELLOW (3050 1625);
FORCEPROP 1 LASTPIN (3050 1625) $PN 1
J 0
(3062 1637);
DISPLAY 0.808511 (3062 1637);
PAINT WHITE (3062 1637);
FORCEPROP 1 LASTPIN (3250 1625) $PN 2
J 0
(3212 1637);
DISPLAY 0.808511 (3212 1637);
PAINT WHITE (3212 1637);
FORCEPROP 0 LAST $SEC 1
J 0
(3250 1675);
DISPLAY 0.680851 (3250 1675);
PAINT MONO (3250 1675);
DISPLAY INVISIBLE (3250 1675);
FORCEPROP 0 LAST CDS_SEC 1
J 0
(3250 1675);
DISPLAY 0.680851 (3250 1675);
DISPLAY INVISIBLE (3250 1675);
FORCEADD Q_RES..1
(3800 2625);
FORCEPROP 1 LAST MATERIAL CHIP
J 0
(4000 2625);
DISPLAY 0.510638 (4000 2625);
PAINT SKYBLUE (4000 2625);
FORCEPROP 1 LAST VALUE 33.2
J 2
(3975 2625);
DISPLAY 0.510638 (3975 2625);
PAINT SKYBLUE (3975 2625);
FORCEPROP 1 LAST PATH I431
J 0
(3750 2775);
DISPLAY 0.978723 (3750 2775);
PAINT WHITE (3750 2775);
DISPLAY INVISIBLE (3750 2775);
FORCEPROP 1 LAST TOLERANCE 1%
J 0
(3725 2725);
DISPLAY 0.510638 (3725 2725);
PAINT SKYBLUE (3725 2725);
DISPLAY INVISIBLE (3725 2725);
FORCEPROP 1 LAST PART_NUMBER CS03322FB03
J 0
(3700 2700);
DISPLAY 0.510638 (3700 2700);
PAINT WHITE (3700 2700);
DISPLAY INVISIBLE (3700 2700);
FORCEPROP 1 LAST PACK_TYPE 0402LF
J 0
(3775 2675);
DISPLAY 0.510638 (3775 2675);
PAINT SKYBLUE (3775 2675);
DISPLAY INVISIBLE (3775 2675);
FORCEPROP 1 LAST WATTAGE 1/16W
J 2
(4150 2725);
DISPLAY 0.510638 (4150 2725);
PAINT SKYBLUE (4150 2725);
DISPLAY INVISIBLE (4150 2725);
FORCEPROP 2 LAST CDS_LIB pure_quanta
J 0
(3800 2625);
DISPLAY INVISIBLE (3800 2625);
FORCEPROP 1 LAST LOCATION R466
J 0
(3600 2625);
DISPLAY 0.702128 (3600 2625);
PAINT YELLOW (3600 2625);
FORCEPROP 0 LAST $SEC 1
J 0
(3575 2675);
DISPLAY 0.680851 (3575 2675);
PAINT MONO (3575 2675);
DISPLAY INVISIBLE (3575 2675);
FORCEPROP 0 LAST CDS_SEC 1
J 0
(3575 2675);
DISPLAY 1.021277 (3575 2675);
DISPLAY INVISIBLE (3575 2675);
FORCEPROP 1 LASTPIN (3700 2625) $PN 1
J 0
(3712 2637);
DISPLAY 0.808511 (3712 2637);
PAINT WHITE (3712 2637);
DISPLAY INVISIBLE (3712 2637);
FORCEPROP 1 LASTPIN (3900 2625) $PN 2
J 0
(3862 2637);
DISPLAY 0.808511 (3862 2637);
PAINT WHITE (3862 2637);
DISPLAY INVISIBLE (3862 2637);
FORCEADD Q_RES..1
(3650 3075);
FORCEPROP 1 LAST VALUE 33.2
J 2
(3825 3075);
DISPLAY 0.510638 (3825 3075);
PAINT SKYBLUE (3825 3075);
FORCEPROP 1 LAST MATERIAL CHIP
J 0
(3850 3075);
DISPLAY 0.510638 (3850 3075);
PAINT SKYBLUE (3850 3075);
FORCEPROP 2 LAST CDS_LIB pure_quanta
J 0
(3650 3075);
DISPLAY INVISIBLE (3650 3075);
FORCEPROP 1 LAST WATTAGE 1/16W
J 2
(4000 3175);
DISPLAY 0.510638 (4000 3175);
PAINT SKYBLUE (4000 3175);
DISPLAY INVISIBLE (4000 3175);
FORCEPROP 1 LAST PACK_TYPE 0402LF
J 0
(3625 3125);
DISPLAY 0.510638 (3625 3125);
PAINT SKYBLUE (3625 3125);
DISPLAY INVISIBLE (3625 3125);
FORCEPROP 1 LAST PART_NUMBER CS03322FB03
J 0
(3550 3150);
DISPLAY 0.510638 (3550 3150);
PAINT WHITE (3550 3150);
DISPLAY INVISIBLE (3550 3150);
FORCEPROP 1 LAST TOLERANCE 1%
J 0
(3575 3175);
DISPLAY 0.510638 (3575 3175);
PAINT SKYBLUE (3575 3175);
DISPLAY INVISIBLE (3575 3175);
FORCEPROP 1 LAST PATH I432
J 0
(3600 3225);
DISPLAY 0.978723 (3600 3225);
PAINT WHITE (3600 3225);
DISPLAY INVISIBLE (3600 3225);
FORCEPROP 1 LAST LOCATION R465
J 0
(3450 3075);
DISPLAY 0.702128 (3450 3075);
PAINT YELLOW (3450 3075);
FORCEPROP 0 LAST $SEC 1
J 0
(3425 3125);
DISPLAY 0.680851 (3425 3125);
PAINT MONO (3425 3125);
DISPLAY INVISIBLE (3425 3125);
FORCEPROP 0 LAST CDS_SEC 1
J 0
(3425 3125);
DISPLAY 1.021277 (3425 3125);
DISPLAY INVISIBLE (3425 3125);
FORCEPROP 1 LASTPIN (3550 3075) $PN 1
J 0
(3562 3087);
DISPLAY 0.808511 (3562 3087);
PAINT WHITE (3562 3087);
DISPLAY INVISIBLE (3562 3087);
FORCEPROP 1 LASTPIN (3750 3075) $PN 2
J 0
(3712 3087);
DISPLAY 0.808511 (3712 3087);
PAINT WHITE (3712 3087);
DISPLAY INVISIBLE (3712 3087);
FORCEADD OFFPAGE..4
(4925 2625);
FORCEPROP 2 LAST $XR0 25 
J 0
(5111 2625);
DISPLAY 0.638298 (5111 2625);
PAINT MONO (5111 2625);
FORCEPROP 2 LAST PATH I433
J 0
(5125 2675);
DISPLAY 0.680851 (5125 2675);
DISPLAY INVISIBLE (5125 2675);
FORCEPROP 2 LAST CDS_LIB standard
J 0
(4925 2625);
DISPLAY INVISIBLE (4925 2625);
FORCEPROP 1 LAST OFFPAGE TRUE
J 0
(5250 2500);
DISPLAY 1.574468 (5250 2500);
PAINT GREEN (5250 2500);
DISPLAY INVISIBLE (5250 2500);
FORCEPROP 1 LAST COMMENT_BODY TRUE
J 0
(4900 2525);
DISPLAY 1.574468 (4900 2525);
PAINT PEACH (4900 2525);
DISPLAY INVISIBLE (4900 2525);
FORCEADD OFFPAGE..2
(4925 3075);
FORCEPROP 2 LAST $XR0 25 
J 0
(5114 3075);
DISPLAY 0.638298 (5114 3075);
PAINT MONO (5114 3075);
FORCEPROP 1 LAST COMMENT_BODY TRUE
J 0
(4880 2980);
DISPLAY 0.872340 (4880 2980);
PAINT PEACH (4880 2980);
DISPLAY INVISIBLE (4880 2980);
FORCEPROP 1 LAST OFFPAGE TRUE
J 0
(5250 2950);
DISPLAY 0.872340 (5250 2950);
PAINT GREEN (5250 2950);
DISPLAY INVISIBLE (5250 2950);
FORCEPROP 2 LAST CDS_LIB standard
J 0
(4925 3075);
DISPLAY INVISIBLE (4925 3075);
FORCEPROP 2 LAST PATH I434
J 0
(5125 3125);
DISPLAY 0.680851 (5125 3125);
DISPLAY INVISIBLE (5125 3125);
FORCEADD 74LVC1G66GV..1
(-1925 4775);
FORCEPROP 2 LAST VALUE 74LVC1G66GV
J 0
(-2075 5150);
DISPLAY 0.680851 (-2075 5150);
FORCEPROP 1 LAST PART_NUMBER AL001G66000
J 0
(-2080 5019);
DISPLAY 0.723404 (-2080 5019);
PAINT GREEN (-2080 5019);
FORCEPROP 1 LAST MATERIAL IC
J 0
(-2080 4930);
DISPLAY 0.723404 (-2080 4930);
PAINT GREEN (-2080 4930);
FORCEPROP 2 LAST PART_TYPE SMLF
J 0
(-2075 5200);
DISPLAY 0.680851 (-2075 5200);
FORCEPROP 1 LAST CDS_LMAN_SYM_OUTLINE -150,150,150,-150
J 0
(-1925 4775);
DISPLAY 0.468085 (-1925 4775);
PAINT GREEN (-1925 4775);
DISPLAY INVISIBLE (-1925 4775);
FORCEPROP 1 LAST PIN_NAMES_ROTATE True
J 0
(-1925 4775);
DISPLAY 0.489362 (-1925 4775);
PAINT GREEN (-1925 4775);
DISPLAY INVISIBLE (-1925 4775);
FORCEPROP 1 LAST PATH I435
J 0
(-1775 4625);
DISPLAY 0.723404 (-1775 4625);
PAINT GREEN (-1775 4625);
DISPLAY INVISIBLE (-1775 4625);
FORCEPROP 2 LAST CDS_LIB pure_quanta
J 0
(-1925 4775);
DISPLAY INVISIBLE (-1925 4775);
FORCEPROP 1 LAST $LOCATION U28
J 0
(-2075 5100);
DISPLAY 0.723404 (-2075 5100);
PAINT GREEN (-2075 5100);
FORCEPROP 0 LASTPIN (-1625 4725) $PN 4
J 0
(-1615 4735);
DISPLAY 0.680851 (-1615 4735);
PAINT MONO (-1615 4735);
FORCEPROP 0 LASTPIN (-2225 4675) $PN 3
J 2
(-2235 4685);
DISPLAY 0.680851 (-2235 4685);
PAINT MONO (-2235 4685);
FORCEPROP 0 LASTPIN (-1625 4875) $PN 5
J 0
(-1615 4885);
DISPLAY 0.680851 (-1615 4885);
PAINT MONO (-1615 4885);
FORCEPROP 0 LASTPIN (-2225 4875) $PN 1
J 2
(-2235 4885);
DISPLAY 0.680851 (-2235 4885);
PAINT MONO (-2235 4885);
FORCEPROP 0 LASTPIN (-2225 4775) $PN 2
J 2
(-2235 4785);
DISPLAY 0.680851 (-2235 4785);
PAINT MONO (-2235 4785);
FORCEPROP 0 LAST CDS_LOCATION U28
J 0
(-2075 5250);
DISPLAY 0.680851 (-2075 5250);
DISPLAY INVISIBLE (-2075 5250);
FORCEPROP 0 LAST $SEC 1
J 0
(-2075 5250);
DISPLAY 0.680851 (-2075 5250);
PAINT MONO (-2075 5250);
DISPLAY INVISIBLE (-2075 5250);
FORCEPROP 0 LAST CDS_SEC 1
J 0
(-2075 5250);
DISPLAY 0.680851 (-2075 5250);
DISPLAY INVISIBLE (-2075 5250);
FORCEADD OFFPAGE..1
(-3275 4875);
FORCEPROP 2 LAST $XR0 10 
J 0
(-3526 4875);
DISPLAY 0.638298 (-3526 4875);
PAINT MONO (-3526 4875);
FORCEPROP 1 LAST COMMENT_BODY TRUE
J 0
(-3150 4775);
DISPLAY 0.872340 (-3150 4775);
PAINT PEACH (-3150 4775);
DISPLAY INVISIBLE (-3150 4775);
FORCEPROP 1 LAST OFFPAGE TRUE
J 0
(-2950 4750);
DISPLAY 0.872340 (-2950 4750);
PAINT GREEN (-2950 4750);
DISPLAY INVISIBLE (-2950 4750);
FORCEPROP 2 LAST CDS_LIB standard
J 0
(-3275 4875);
DISPLAY INVISIBLE (-3275 4875);
FORCEPROP 2 LAST PATH I436
J 0
(-3525 4925);
DISPLAY 0.680851 (-3525 4925);
DISPLAY INVISIBLE (-3525 4925);
FORCEADD UNIVERSAL_GND..1
(-2325 4550);
FORCEPROP 3 LASTPIN (-2325 4600) SIG_NAME GND\g
J 0
(-2315 4610);
DISPLAY 0.659574 (-2315 4610);
PAINT MONO (-2315 4610);
DISPLAY INVISIBLE (-2315 4610);
FORCEPROP 1 LAST HDL_POWER GND
J 1
(-2300 4475);
DISPLAY 0.702128 (-2300 4475);
PAINT GREEN (-2300 4475);
DISPLAY INVISIBLE (-2300 4475);
FORCEPROP 1 LAST PATH I439
J 0
(-2250 4550);
DISPLAY 0.872340 (-2250 4550);
PAINT AQUA (-2250 4550);
DISPLAY INVISIBLE (-2250 4550);
FORCEPROP 2 LAST CDS_LIB logical_power
J 0
(-2325 4550);
DISPLAY INVISIBLE (-2325 4550);
FORCEADD Q_CAP..1
R 2
(-1175 5025);
FORCEPROP 1 LAST VOLTAGE 25V
J 2
(-1225 5000);
DISPLAY 0.510638 (-1225 5000);
PAINT SKYBLUE (-1225 5000);
FORCEPROP 1 LAST PACK_TYPE 0402
J 2
(-1225 4850);
DISPLAY 0.510638 (-1225 4850);
PAINT SKYBLUE (-1225 4850);
FORCEPROP 1 LAST PART_NUMBER CH4104K1B00
J 2
(-1225 4800);
DISPLAY 0.510638 (-1225 4800);
PAINT WHITE (-1225 4800);
FORCEPROP 1 LAST MATERIAL X7R
J 2
(-1225 4900);
DISPLAY 0.510638 (-1225 4900);
PAINT SKYBLUE (-1225 4900);
FORCEPROP 1 LAST TOLERANCE 10%
J 2
(-1225 4950);
DISPLAY 0.510638 (-1225 4950);
PAINT SKYBLUE (-1225 4950);
FORCEPROP 1 LAST VALUE 0.1UF
J 2
(-1225 5050);
DISPLAY 0.510638 (-1225 5050);
PAINT SKYBLUE (-1225 5050);
FORCEPROP 1 LAST PATH I440
J 2
(-1225 5175);
DISPLAY 0.978723 (-1225 5175);
PAINT WHITE (-1225 5175);
DISPLAY INVISIBLE (-1225 5175);
FORCEPROP 2 LAST CDS_LIB pure_quanta
J 0
(-1175 5025);
DISPLAY INVISIBLE (-1175 5025);
FORCEPROP 1 LAST $LOCATION C180
J 2
(-1225 5075);
DISPLAY 0.978723 (-1225 5075);
FORCEPROP 1 LASTPIN (-1175 5125) $PN 1
J 2
(-1185 5105);
DISPLAY 0.787234 (-1185 5105);
PAINT MONO (-1185 5105);
FORCEPROP 1 LASTPIN (-1175 4925) $PN 2
J 2
(-1185 4905);
DISPLAY 0.787234 (-1185 4905);
PAINT MONO (-1185 4905);
FORCEPROP 0 LAST CDS_LOCATION C180
J 0
(-1225 5175);
DISPLAY 0.680851 (-1225 5175);
DISPLAY INVISIBLE (-1225 5175);
FORCEPROP 0 LAST $SEC 1
J 0
(-1225 5175);
DISPLAY 0.680851 (-1225 5175);
PAINT MONO (-1225 5175);
DISPLAY INVISIBLE (-1225 5175);
FORCEPROP 0 LAST CDS_SEC 1
J 0
(-1225 5175);
DISPLAY 0.680851 (-1225 5175);
DISPLAY INVISIBLE (-1225 5175);
FORCEADD VCCAUX15..1
(-1600 5200);
FORCEPROP 3 LASTPIN (-1600 5150) SIG_NAME P3V3_LDO\g
J 0
(-1590 5160);
DISPLAY 0.659574 (-1590 5160);
PAINT MONO (-1590 5160);
DISPLAY INVISIBLE (-1590 5160);
FORCEPROP 1 LAST HDL_POWER P3V3_LDO
J 1
(-1600 5250);
DISPLAY 0.702128 (-1600 5250);
PAINT GREEN (-1600 5250);
FORCEPROP 1 LAST PATH I441
J 0
(-1550 5225);
DISPLAY 0.872340 (-1550 5225);
PAINT AQUA (-1550 5225);
DISPLAY INVISIBLE (-1550 5225);
FORCEPROP 2 LAST CDS_LIB logical_power
J 0
(-1600 5200);
DISPLAY INVISIBLE (-1600 5200);
FORCEADD UNIVERSAL_GND..1
(-1175 4850);
FORCEPROP 3 LASTPIN (-1175 4900) SIG_NAME GND\g
J 0
(-1165 4910);
DISPLAY 0.659574 (-1165 4910);
PAINT MONO (-1165 4910);
DISPLAY INVISIBLE (-1165 4910);
FORCEPROP 2 LAST CDS_LIB logical_power
J 0
(-1175 4850);
DISPLAY INVISIBLE (-1175 4850);
FORCEPROP 1 LAST PATH I442
J 0
(-1100 4850);
DISPLAY 0.872340 (-1100 4850);
PAINT AQUA (-1100 4850);
DISPLAY INVISIBLE (-1100 4850);
FORCEPROP 1 LAST HDL_POWER GND
J 1
(-1150 4775);
DISPLAY 0.702128 (-1150 4775);
PAINT GREEN (-1150 4775);
DISPLAY INVISIBLE (-1150 4775);
FORCEADD OFFPAGE..1
(-1675 4475);
FORCEPROP 2 LAST CDS_LIB standard
J 0
(-1675 4475);
DISPLAY INVISIBLE (-1675 4475);
FORCEPROP 2 LAST PATH I443
J 0
(-1625 4550);
DISPLAY 0.680851 (-1625 4550);
DISPLAY INVISIBLE (-1625 4550);
FORCEPROP 1 LAST OFFPAGE TRUE
J 0
(-1350 4350);
DISPLAY 0.872340 (-1350 4350);
DISPLAY INVISIBLE (-1350 4350);
FORCEPROP 1 LAST COMMENT_BODY TRUE
J 0
(-1550 4375);
DISPLAY 0.872340 (-1550 4375);
PAINT PEACH (-1550 4375);
DISPLAY INVISIBLE (-1550 4375);
FORCEADD OFFPAGE..2
(-2300 4475);
FORCEPROP 1 LAST OFFPAGE TRUE
J 0
(-1975 4350);
DISPLAY 0.872340 (-1975 4350);
PAINT GREEN (-1975 4350);
DISPLAY INVISIBLE (-1975 4350);
FORCEPROP 1 LAST COMMENT_BODY TRUE
J 0
(-2345 4380);
DISPLAY 0.872340 (-2345 4380);
PAINT PEACH (-2345 4380);
DISPLAY INVISIBLE (-2345 4380);
FORCEPROP 2 LAST PATH I446
J 0
(-2125 4550);
DISPLAY 0.680851 (-2125 4550);
DISPLAY INVISIBLE (-2125 4550);
FORCEPROP 2 LAST CDS_LIB standard
J 0
(-2300 4475);
DISPLAY INVISIBLE (-2300 4475);
FORCEADD Q_RES..2
(-3350 4625);
FORCEPROP 1 LAST VALUE 0
J 0
(-3325 4675);
DISPLAY 0.638298 (-3325 4675);
FORCEPROP 1 LAST MATERIAL CHIP
J 0
(-3325 4625);
DISPLAY 0.638298 (-3325 4625);
FORCEPROP 1 LAST PART_NUMBER CS00002JB13
J 0
(-3325 4575);
DISPLAY 0.638298 (-3325 4575);
FORCEPROP 1 LAST PATH I447
J 0
(-3300 4800);
DISPLAY 0.978723 (-3300 4800);
PAINT WHITE (-3300 4800);
DISPLAY INVISIBLE (-3300 4800);
FORCEPROP 2 LAST CDS_LIB pure_quanta
J 0
(-3350 4625);
DISPLAY INVISIBLE (-3350 4625);
FORCEPROP 1 LAST PACK_TYPE 0402LF
J 0
(-3310 4450);
DISPLAY 0.638298 (-3310 4450);
DISPLAY INVISIBLE (-3310 4450);
FORCEPROP 1 LAST WATTAGE 1/16W
J 0
(-3310 4600);
DISPLAY 0.638298 (-3310 4600);
DISPLAY INVISIBLE (-3310 4600);
FORCEPROP 1 LAST TOLERANCE 5%
J 0
(-3305 4650);
DISPLAY 0.638298 (-3305 4650);
DISPLAY INVISIBLE (-3305 4650);
FORCEPROP 1 LAST LOCATION R392
J 0
(-3325 4500);
DISPLAY 0.978723 (-3325 4500);
FORCEPROP 1 LASTPIN (-3350 4725) $PN 1
J 0
(-3345 4687);
DISPLAY 0.787234 (-3345 4687);
PAINT MONO (-3345 4687);
FORCEPROP 1 LASTPIN (-3350 4525) $PN 2
J 0
(-3345 4535);
DISPLAY 0.787234 (-3345 4535);
PAINT MONO (-3345 4535);
FORCEPROP 0 LAST $SEC 1
J 0
(-3325 4725);
DISPLAY 0.680851 (-3325 4725);
PAINT MONO (-3325 4725);
DISPLAY INVISIBLE (-3325 4725);
FORCEPROP 0 LAST CDS_SEC 1
J 0
(-3325 4725);
DISPLAY 0.680851 (-3325 4725);
DISPLAY INVISIBLE (-3325 4725);
FORCEADD Q_RES..2
(-775 4625);
FORCEPROP 1 LAST VALUE 0
J 0
(-750 4675);
DISPLAY 0.638298 (-750 4675);
FORCEPROP 1 LAST MATERIAL CHIP
J 0
(-750 4625);
DISPLAY 0.638298 (-750 4625);
FORCEPROP 1 LAST PART_NUMBER CS00002JB13
J 0
(-750 4575);
DISPLAY 0.638298 (-750 4575);
FORCEPROP 1 LAST PATH I448
J 0
(-725 4800);
DISPLAY 0.978723 (-725 4800);
PAINT WHITE (-725 4800);
DISPLAY INVISIBLE (-725 4800);
FORCEPROP 2 LAST CDS_LIB pure_quanta
J 0
(-775 4625);
DISPLAY INVISIBLE (-775 4625);
FORCEPROP 1 LAST TOLERANCE 5%
J 0
(-730 4650);
DISPLAY 0.638298 (-730 4650);
DISPLAY INVISIBLE (-730 4650);
FORCEPROP 1 LAST WATTAGE 1/16W
J 0
(-735 4600);
DISPLAY 0.638298 (-735 4600);
DISPLAY INVISIBLE (-735 4600);
FORCEPROP 1 LAST PACK_TYPE 0402LF
J 0
(-735 4450);
DISPLAY 0.638298 (-735 4450);
DISPLAY INVISIBLE (-735 4450);
FORCEPROP 1 LAST $LOCATION R395
J 0
(-750 4525);
DISPLAY 0.808511 (-750 4525);
FORCEPROP 1 LASTPIN (-775 4725) $PN 1
J 0
(-770 4687);
DISPLAY 0.787234 (-770 4687);
PAINT MONO (-770 4687);
FORCEPROP 1 LASTPIN (-775 4525) $PN 2
J 0
(-770 4535);
DISPLAY 0.787234 (-770 4535);
PAINT MONO (-770 4535);
FORCEPROP 0 LAST CDS_LOCATION R395
J 0
(-750 4725);
DISPLAY 0.680851 (-750 4725);
DISPLAY INVISIBLE (-750 4725);
FORCEPROP 0 LAST $SEC 1
J 0
(-750 4725);
DISPLAY 0.680851 (-750 4725);
PAINT MONO (-750 4725);
DISPLAY INVISIBLE (-750 4725);
FORCEPROP 0 LAST CDS_SEC 1
J 0
(-750 4725);
DISPLAY 0.680851 (-750 4725);
DISPLAY INVISIBLE (-750 4725);
FORCEADD Q_RES..1
(3250 4025);
FORCEPROP 1 LAST PART_NUMBER CS09092FB15
J 0
(3125 4075);
DISPLAY 0.638298 (3125 4075);
FORCEPROP 1 LAST VALUE 90.9
J 2
(3500 4025);
DISPLAY 0.638298 (3500 4025);
FORCEPROP 1 LAST MATERIAL CHIP
J 0
(3525 4025);
DISPLAY 0.638298 (3525 4025);
FORCEPROP 1 LAST PATH I449
J 0
(3200 4175);
DISPLAY 0.978723 (3200 4175);
PAINT WHITE (3200 4175);
DISPLAY INVISIBLE (3200 4175);
FORCEPROP 2 LAST CDS_LIB pure_quanta
J 0
(3250 4025);
DISPLAY INVISIBLE (3250 4025);
FORCEPROP 1 LAST TOLERANCE 1%
J 0
(3250 3925);
DISPLAY 0.638298 (3250 3925);
DISPLAY INVISIBLE (3250 3925);
FORCEPROP 1 LAST WATTAGE 1/16W
J 2
(3225 3875);
DISPLAY 0.638298 (3225 3875);
DISPLAY INVISIBLE (3225 3875);
FORCEPROP 1 LAST PACK_TYPE 0402LF
J 0
(3500 3875);
DISPLAY 0.638298 (3500 3875);
DISPLAY INVISIBLE (3500 3875);
FORCEPROP 1 LAST LOCATION R468
J 0
(3000 4025);
DISPLAY 0.787234 (3000 4025);
FORCEPROP 1 LASTPIN (3150 4025) $PN 1
J 0
(3162 4037);
DISPLAY 0.787234 (3162 4037);
PAINT MONO (3162 4037);
FORCEPROP 1 LASTPIN (3350 4025) $PN 2
J 0
(3312 4037);
DISPLAY 0.787234 (3312 4037);
PAINT MONO (3312 4037);
FORCEPROP 0 LAST $SEC 1
J 0
(3125 4125);
DISPLAY 0.680851 (3125 4125);
PAINT MONO (3125 4125);
DISPLAY INVISIBLE (3125 4125);
FORCEPROP 0 LAST CDS_SEC 1
J 0
(3125 4125);
DISPLAY 0.680851 (3125 4125);
DISPLAY INVISIBLE (3125 4125);
FORCEADD Q_RES..1
(3150 1775);
FORCEPROP 1 LAST PART_NUMBER CS02202FB02
J 0
(2950 1850);
DISPLAY 0.638298 (2950 1850);
FORCEPROP 1 LAST MATERIAL CHIP
J 0
(3325 1775);
DISPLAY 0.638298 (3325 1775);
PAINT SKYBLUE (3325 1775);
FORCEPROP 1 LAST VALUE 22
J 2
(3300 1775);
DISPLAY 0.638298 (3300 1775);
PAINT SKYBLUE (3300 1775);
FORCEPROP 1 LAST TOLERANCE 1%
J 0
(3150 1675);
DISPLAY 0.978723 (3150 1675);
DISPLAY INVISIBLE (3150 1675);
FORCEPROP 1 LAST PACK_TYPE 0402LF
J 0
(3400 1625);
DISPLAY 0.978723 (3400 1625);
DISPLAY INVISIBLE (3400 1625);
FORCEPROP 1 LAST WATTAGE 1/16W
J 2
(3125 1625);
DISPLAY 0.978723 (3125 1625);
DISPLAY INVISIBLE (3125 1625);
FORCEPROP 1 LAST PATH I451
J 0
(3100 1925);
DISPLAY 0.978723 (3100 1925);
PAINT WHITE (3100 1925);
DISPLAY INVISIBLE (3100 1925);
FORCEPROP 2 LAST CDS_LIB pure_quanta
J 0
(3150 1775);
DISPLAY INVISIBLE (3150 1775);
FORCEPROP 1 LAST LOCATION R171
J 0
(2925 1775);
DISPLAY 0.787234 (2925 1775);
FORCEPROP 1 LASTPIN (3050 1775) $PN 1
J 0
(3062 1787);
DISPLAY 0.787234 (3062 1787);
PAINT MONO (3062 1787);
FORCEPROP 1 LASTPIN (3250 1775) $PN 2
J 0
(3212 1787);
DISPLAY 0.787234 (3212 1787);
PAINT MONO (3212 1787);
FORCEPROP 0 LAST $SEC 1
J 0
(2950 1900);
DISPLAY 0.680851 (2950 1900);
PAINT MONO (2950 1900);
DISPLAY INVISIBLE (2950 1900);
FORCEPROP 0 LAST CDS_SEC 1
J 0
(2950 1900);
DISPLAY 0.680851 (2950 1900);
DISPLAY INVISIBLE (2950 1900);
FORCEADD Q_RES..1
(3150 1725);
FORCEPROP 1 LAST MATERIAL CHIP
J 0
(3325 1725);
DISPLAY 0.638298 (3325 1725);
PAINT SKYBLUE (3325 1725);
FORCEPROP 1 LAST VALUE 22
J 2
(3300 1725);
DISPLAY 0.638298 (3300 1725);
PAINT SKYBLUE (3300 1725);
FORCEPROP 1 LAST WATTAGE 1/16W
J 2
(3125 1575);
DISPLAY 0.978723 (3125 1575);
DISPLAY INVISIBLE (3125 1575);
FORCEPROP 1 LAST PACK_TYPE 0402LF
J 0
(3400 1575);
DISPLAY 0.978723 (3400 1575);
DISPLAY INVISIBLE (3400 1575);
FORCEPROP 1 LAST TOLERANCE 1%
J 0
(3150 1625);
DISPLAY 0.978723 (3150 1625);
DISPLAY INVISIBLE (3150 1625);
FORCEPROP 1 LAST PATH I452
J 0
(3100 1875);
DISPLAY 0.978723 (3100 1875);
PAINT WHITE (3100 1875);
DISPLAY INVISIBLE (3100 1875);
FORCEPROP 2 LAST CDS_LIB pure_quanta
J 0
(3150 1725);
DISPLAY INVISIBLE (3150 1725);
FORCEPROP 1 LAST PART_NUMBER CS02202FB02
J 0
(3100 1825);
DISPLAY 0.638298 (3100 1825);
DISPLAY INVISIBLE (3100 1825);
FORCEPROP 1 LAST LOCATION R172
J 0
(2925 1725);
DISPLAY 0.787234 (2925 1725);
FORCEPROP 1 LASTPIN (3050 1725) $PN 1
J 0
(3062 1737);
DISPLAY 0.787234 (3062 1737);
PAINT MONO (3062 1737);
FORCEPROP 1 LASTPIN (3250 1725) $PN 2
J 0
(3212 1737);
DISPLAY 0.787234 (3212 1737);
PAINT MONO (3212 1737);
FORCEPROP 0 LAST $SEC 1
J 0
(3325 1775);
DISPLAY 0.680851 (3325 1775);
PAINT MONO (3325 1775);
DISPLAY INVISIBLE (3325 1775);
FORCEPROP 0 LAST CDS_SEC 1
J 0
(3325 1775);
DISPLAY 0.680851 (3325 1775);
DISPLAY INVISIBLE (3325 1775);
FORCEADD Q_RES..1
(3150 1675);
FORCEPROP 1 LAST MATERIAL CHIP
J 0
(3325 1675);
DISPLAY 0.638298 (3325 1675);
PAINT SKYBLUE (3325 1675);
FORCEPROP 1 LAST VALUE 22
J 2
(3300 1675);
DISPLAY 0.638298 (3300 1675);
PAINT SKYBLUE (3300 1675);
FORCEPROP 1 LAST WATTAGE 1/16W
J 2
(3125 1525);
DISPLAY 0.978723 (3125 1525);
DISPLAY INVISIBLE (3125 1525);
FORCEPROP 1 LAST PACK_TYPE 0402LF
J 0
(3400 1525);
DISPLAY 0.978723 (3400 1525);
DISPLAY INVISIBLE (3400 1525);
FORCEPROP 1 LAST TOLERANCE 1%
J 0
(3150 1575);
DISPLAY 0.978723 (3150 1575);
DISPLAY INVISIBLE (3150 1575);
FORCEPROP 1 LAST PATH I453
J 0
(3100 1825);
DISPLAY 0.978723 (3100 1825);
PAINT WHITE (3100 1825);
DISPLAY INVISIBLE (3100 1825);
FORCEPROP 2 LAST CDS_LIB pure_quanta
J 0
(3150 1675);
DISPLAY INVISIBLE (3150 1675);
FORCEPROP 1 LAST PART_NUMBER CS02202FB02
J 0
(3100 1775);
DISPLAY 0.638298 (3100 1775);
DISPLAY INVISIBLE (3100 1775);
FORCEPROP 1 LAST LOCATION R173
J 0
(2925 1675);
DISPLAY 0.787234 (2925 1675);
FORCEPROP 1 LASTPIN (3050 1675) $PN 1
J 0
(3062 1687);
DISPLAY 0.787234 (3062 1687);
PAINT MONO (3062 1687);
FORCEPROP 1 LASTPIN (3250 1675) $PN 2
J 0
(3212 1687);
DISPLAY 0.787234 (3212 1687);
PAINT MONO (3212 1687);
FORCEPROP 0 LAST $SEC 1
J 0
(3325 1725);
DISPLAY 0.680851 (3325 1725);
PAINT MONO (3325 1725);
DISPLAY INVISIBLE (3325 1725);
FORCEPROP 0 LAST CDS_SEC 1
J 0
(3325 1725);
DISPLAY 0.680851 (3325 1725);
DISPLAY INVISIBLE (3325 1725);
FORCEADD Q_LED..1
(825 -525);
FORCEPROP 2 LAST MANUF_PN 19-213/GVC-AMNB/3T
J 0
(725 -250);
DISPLAY 0.808511 (725 -250);
FORCEPROP 2 LAST COLOR LED_GREEN
J 0
(725 -200);
DISPLAY 0.808511 (725 -200);
FORCEPROP 1 LAST MATERIAL IC
J 0
(725 -445);
DISPLAY 0.510638 (725 -445);
PAINT SKYBLUE (725 -445);
FORCEPROP 1 LAST PART_NUMBER BEGR0278Z00
J 0
(725 -390);
DISPLAY 0.510638 (725 -390);
PAINT WHITE (725 -390);
FORCEPROP 2 LAST PACK_TYPE SMLF
J 0
(725 -300);
DISPLAY 0.510638 (725 -300);
PAINT SKYBLUE (725 -300);
FORCEPROP 1 LAST PATH I46
J 0
(950 -445);
DISPLAY 0.723404 (950 -445);
PAINT GREEN (950 -445);
DISPLAY INVISIBLE (950 -445);
FORCEPROP 2 LAST CDS_LIB pure_quanta
J 0
(825 -525);
DISPLAY INVISIBLE (825 -525);
FORCEPROP 1 LAST NEEDS_NO_SIZE TRUE
J 0
(825 -525);
DISPLAY 0.468085 (825 -525);
PAINT GREEN (825 -525);
DISPLAY INVISIBLE (825 -525);
FORCEPROP 1 LAST LOCATION D8
J 0
(725 -340);
DISPLAY 0.702128 (725 -340);
PAINT YELLOW (725 -340);
FORCEPROP 0 LASTPIN (675 -525) $PN A
J 2
(665 -515);
DISPLAY 0.680851 (665 -515);
PAINT MONO (665 -515);
FORCEPROP 0 LASTPIN (975 -525) $PN C
J 0
(985 -515);
DISPLAY 0.680851 (985 -515);
PAINT MONO (985 -515);
FORCEPROP 2 LAST $SEC 1
J 0
(725 -150);
DISPLAY 0.680851 (725 -150);
PAINT MONO (725 -150);
DISPLAY INVISIBLE (725 -150);
FORCEPROP 0 LAST CDS_SEC 1
J 0
(725 -150);
DISPLAY 0.680851 (725 -150);
PAINT MONO (725 -150);
DISPLAY INVISIBLE (725 -150);
FORCEADD OFFPAGE..4
(1950 -525);
FORCEPROP 2 LAST $XR0 15 
J 0
(2136 -525);
DISPLAY 0.638298 (2136 -525);
PAINT MONO (2136 -525);
FORCEPROP 2 LAST PATH I48
J 0
(2150 -475);
DISPLAY 1.021277 (2150 -475);
DISPLAY INVISIBLE (2150 -475);
FORCEPROP 1 LAST COMMENT_BODY TRUE
J 0
(1925 -625);
DISPLAY 1.574468 (1925 -625);
PAINT PEACH (1925 -625);
DISPLAY INVISIBLE (1925 -625);
FORCEPROP 1 LAST OFFPAGE TRUE
J 0
(2275 -650);
DISPLAY 1.574468 (2275 -650);
PAINT GREEN (2275 -650);
DISPLAY INVISIBLE (2275 -650);
FORCEPROP 2 LAST CDS_LIB standard
J 0
(1950 -525);
DISPLAY INVISIBLE (1950 -525);
FORCEADD Q_RES..1
(-2800 0);
FORCEPROP 1 LAST VALUE 0
J 2
(-2625 0);
DISPLAY 0.510638 (-2625 0);
PAINT SKYBLUE (-2625 0);
FORCEPROP 1 LAST TOLERANCE 5%
J 0
(-2225 100);
DISPLAY 0.510638 (-2225 100);
PAINT SKYBLUE (-2225 100);
FORCEPROP 1 LAST PACK_TYPE 0402LF
J 0
(-2500 100);
DISPLAY 0.510638 (-2500 100);
PAINT SKYBLUE (-2500 100);
FORCEPROP 1 LAST MATERIAL CHIP
J 0
(-2700 100);
DISPLAY 0.510638 (-2700 100);
PAINT SKYBLUE (-2700 100);
FORCEPROP 1 LAST WATTAGE 1/16W
J 2
(-2725 100);
DISPLAY 0.510638 (-2725 100);
PAINT SKYBLUE (-2725 100);
FORCEPROP 1 LAST PART_NUMBER CS00002JB13
J 0
(-2850 175);
DISPLAY 0.510638 (-2850 175);
PAINT WHITE (-2850 175);
FORCEPROP 1 LAST PATH I5
J 0
(-2850 150);
DISPLAY 0.978723 (-2850 150);
PAINT WHITE (-2850 150);
DISPLAY INVISIBLE (-2850 150);
FORCEPROP 2 LAST CDS_LIB pure_quanta
J 0
(-2800 0);
DISPLAY INVISIBLE (-2800 0);
FORCEPROP 1 LAST LOCATION R155
J 0
(-3100 0);
DISPLAY 0.702128 (-3100 0);
PAINT YELLOW (-3100 0);
FORCEPROP 1 LASTPIN (-2900 0) $PN 1
J 0
(-2888 12);
DISPLAY 0.808511 (-2888 12);
PAINT WHITE (-2888 12);
FORCEPROP 1 LASTPIN (-2700 0) $PN 2
J 0
(-2738 12);
DISPLAY 0.808511 (-2738 12);
PAINT WHITE (-2738 12);
FORCEPROP 0 LAST $SEC 1
J 0
(-2850 225);
DISPLAY 0.680851 (-2850 225);
PAINT MONO (-2850 225);
DISPLAY INVISIBLE (-2850 225);
FORCEPROP 0 LAST CDS_SEC 1
J 0
(-2850 225);
DISPLAY 0.680851 (-2850 225);
DISPLAY INVISIBLE (-2850 225);
FORCEADD Q_RES..1
(-1750 3025);
FORCEPROP 1 LAST VALUE 33.2
J 0
(-1675 3025);
DISPLAY 0.510638 (-1675 3025);
PAINT SKYBLUE (-1675 3025);
FORCEPROP 1 LAST MATERIAL CHIP
J 0
(-1575 3025);
DISPLAY 0.510638 (-1575 3025);
PAINT SKYBLUE (-1575 3025);
FORCEPROP 1 LAST TOLERANCE 1%
J 0
(-1625 3025);
DISPLAY 0.510638 (-1625 3025);
PAINT SKYBLUE (-1625 3025);
DISPLAY INVISIBLE (-1625 3025);
FORCEPROP 1 LAST PART_NUMBER CS03322FB03
J 0
(-1625 3075);
DISPLAY 0.510638 (-1625 3075);
PAINT WHITE (-1625 3075);
DISPLAY INVISIBLE (-1625 3075);
FORCEPROP 1 LAST PACK_TYPE 0402LF
J 0
(-1500 2875);
DISPLAY 0.510638 (-1500 2875);
PAINT SKYBLUE (-1500 2875);
DISPLAY INVISIBLE (-1500 2875);
FORCEPROP 1 LAST WATTAGE 1/16W
J 2
(-1775 2875);
DISPLAY 0.510638 (-1775 2875);
PAINT SKYBLUE (-1775 2875);
DISPLAY INVISIBLE (-1775 2875);
FORCEPROP 1 LAST PATH I50
J 0
(-1800 3175);
DISPLAY 0.978723 (-1800 3175);
PAINT WHITE (-1800 3175);
DISPLAY INVISIBLE (-1800 3175);
FORCEPROP 2 LAST CDS_LIB pure_quanta
J 0
(-1750 3025);
DISPLAY INVISIBLE (-1750 3025);
FORCEPROP 1 LAST LOCATION R166
J 0
(-2000 3025);
DISPLAY 0.702128 (-2000 3025);
PAINT YELLOW (-2000 3025);
FORCEPROP 0 LAST $SEC 1
J 0
(-1800 3175);
DISPLAY INVISIBLE (-1800 3175);
FORCEPROP 0 LAST CDS_SEC 1
J 0
(-1800 3175);
DISPLAY INVISIBLE (-1800 3175);
FORCEPROP 1 LASTPIN (-1850 3025) $PN 1
J 0
(-1838 3037);
DISPLAY 0.808511 (-1838 3037);
PAINT WHITE (-1838 3037);
DISPLAY INVISIBLE (-1838 3037);
FORCEPROP 1 LASTPIN (-1650 3025) $PN 2
J 0
(-1688 3037);
DISPLAY 0.808511 (-1688 3037);
PAINT WHITE (-1688 3037);
DISPLAY INVISIBLE (-1688 3037);
FORCEADD OFFPAGE..1
(-2975 3375);
FORCEPROP 2 LAST $XR0 27 
J 0
(-3196 3375);
DISPLAY 0.638298 (-3196 3375);
PAINT MONO (-3196 3375);
FORCEPROP 2 LAST $XR1 34 
J 0
(-3286 3375);
DISPLAY 0.638298 (-3286 3375);
PAINT MONO (-3286 3375);
FORCEPROP 2 LAST CDS_LIB standard
J 0
(-2975 3375);
DISPLAY INVISIBLE (-2975 3375);
FORCEPROP 1 LAST OFFPAGE TRUE
J 0
(-2650 3250);
DISPLAY 0.872340 (-2650 3250);
DISPLAY INVISIBLE (-2650 3250);
FORCEPROP 1 LAST COMMENT_BODY TRUE
J 0
(-2850 3275);
DISPLAY 0.872340 (-2850 3275);
PAINT GREEN (-2850 3275);
DISPLAY INVISIBLE (-2850 3275);
FORCEPROP 2 LAST PATH I55
J 0
(-3175 3425);
DISPLAY 1.021277 (-3175 3425);
DISPLAY INVISIBLE (-3175 3425);
FORCEADD UNIVERSAL_POWER..1
(-3175 250);
FORCEPROP 3 LASTPIN (-3175 200) SIG_NAME P3V3_AUX\g
J 0
(-3165 210);
DISPLAY 0.659574 (-3165 210);
PAINT MONO (-3165 210);
DISPLAY INVISIBLE (-3165 210);
FORCEPROP 1 LAST HDL_POWER P3V3_AUX
J 1
(-3175 300);
DISPLAY 0.702128 (-3175 300);
PAINT GREEN (-3175 300);
FORCEPROP 2 LAST CDS_LIB logical_power
J 0
(-3175 250);
DISPLAY INVISIBLE (-3175 250);
FORCEPROP 1 LAST PATH I6
J 0
(-3125 275);
DISPLAY 0.872340 (-3125 275);
PAINT AQUA (-3125 275);
DISPLAY INVISIBLE (-3125 275);
FORCEADD Q_RES..1
(2875 2025);
FORCEPROP 1 LAST VALUE 33.2
J 0
(3000 2025);
DISPLAY 0.510638 (3000 2025);
PAINT SKYBLUE (3000 2025);
FORCEPROP 1 LAST MATERIAL CHIP
J 0
(3100 2025);
DISPLAY 0.510638 (3100 2025);
PAINT SKYBLUE (3100 2025);
FORCEPROP 1 LAST TOLERANCE 1%
J 0
(3000 2025);
DISPLAY 0.510638 (3000 2025);
PAINT SKYBLUE (3000 2025);
DISPLAY INVISIBLE (3000 2025);
FORCEPROP 1 LAST PART_NUMBER CS03322FB03
J 0
(2825 2125);
DISPLAY 0.510638 (2825 2125);
PAINT WHITE (2825 2125);
DISPLAY INVISIBLE (2825 2125);
FORCEPROP 1 LAST PACK_TYPE 0402LF
J 0
(3125 1875);
DISPLAY 0.510638 (3125 1875);
PAINT SKYBLUE (3125 1875);
DISPLAY INVISIBLE (3125 1875);
FORCEPROP 1 LAST WATTAGE 1/16W
J 2
(2850 1875);
DISPLAY 0.510638 (2850 1875);
PAINT SKYBLUE (2850 1875);
DISPLAY INVISIBLE (2850 1875);
FORCEPROP 1 LAST PATH I67
J 0
(2825 2175);
DISPLAY 0.978723 (2825 2175);
PAINT WHITE (2825 2175);
DISPLAY INVISIBLE (2825 2175);
FORCEPROP 2 LAST CDS_LIB pure_quanta
J 0
(2875 2025);
DISPLAY INVISIBLE (2875 2025);
FORCEPROP 1 LAST LOCATION R170
J 0
(2675 2025);
DISPLAY 0.702128 (2675 2025);
PAINT YELLOW (2675 2025);
FORCEPROP 1 LASTPIN (2775 2025) $PN 1
J 0
(2787 2037);
DISPLAY 0.808511 (2787 2037);
PAINT WHITE (2787 2037);
FORCEPROP 1 LASTPIN (2975 2025) $PN 2
J 0
(2937 2037);
DISPLAY 0.808511 (2937 2037);
PAINT WHITE (2937 2037);
FORCEPROP 2 LAST $SEC 1
J 0
(2825 2225);
DISPLAY 0.680851 (2825 2225);
PAINT MONO (2825 2225);
DISPLAY INVISIBLE (2825 2225);
FORCEPROP 0 LAST CDS_SEC 1
J 0
(2825 2225);
DISPLAY 0.680851 (2825 2225);
PAINT MONO (2825 2225);
DISPLAY INVISIBLE (2825 2225);
FORCEADD OFFPAGE..2
(4475 1075);
FORCEPROP 2 LAST $XR0 13 
J 0
(4664 1075);
DISPLAY 0.638298 (4664 1075);
PAINT MONO (4664 1075);
FORCEPROP 2 LAST $XR1 34 
J 0
(4754 1075);
DISPLAY 0.638298 (4754 1075);
PAINT MONO (4754 1075);
FORCEPROP 2 LAST PATH I69
J 0
(4675 1125);
DISPLAY 1.021277 (4675 1125);
DISPLAY INVISIBLE (4675 1125);
FORCEPROP 1 LAST COMMENT_BODY TRUE
J 0
(4430 980);
DISPLAY 0.872340 (4430 980);
PAINT PEACH (4430 980);
DISPLAY INVISIBLE (4430 980);
FORCEPROP 1 LAST OFFPAGE TRUE
J 0
(4800 950);
DISPLAY 0.872340 (4800 950);
PAINT GREEN (4800 950);
DISPLAY INVISIBLE (4800 950);
FORCEPROP 2 LAST CDS_LIB standard
J 0
(4475 1075);
DISPLAY INVISIBLE (4475 1075);
FORCEADD OFFPAGE..2
R 2
(-3425 1975);
FORCEPROP 2 LAST $XR1 36 
J 0
(-3769 1975);
DISPLAY 0.638298 (-3769 1975);
PAINT MONO (-3769 1975);
FORCEPROP 2 LAST $XR0 48 
J 0
(-3679 1975);
DISPLAY 0.638298 (-3679 1975);
PAINT MONO (-3679 1975);
FORCEPROP 2 LAST PATH I7
J 0
(-3625 2025);
DISPLAY 1.021277 (-3625 2025);
DISPLAY INVISIBLE (-3625 2025);
FORCEPROP 1 LAST COMMENT_BODY TRUE
J 2
(-3380 1880);
DISPLAY 0.872340 (-3380 1880);
PAINT PEACH (-3380 1880);
DISPLAY INVISIBLE (-3380 1880);
FORCEPROP 1 LAST OFFPAGE TRUE
J 2
(-3750 1850);
DISPLAY 0.872340 (-3750 1850);
PAINT GREEN (-3750 1850);
DISPLAY INVISIBLE (-3750 1850);
FORCEPROP 2 LAST CDS_LIB standard
J 0
(-3425 1975);
DISPLAY INVISIBLE (-3425 1975);
FORCEADD OFFPAGE..2
(4450 1675);
FORCEPROP 2 LAST $XR0 10 
J 0
(4639 1675);
DISPLAY 0.638298 (4639 1675);
PAINT MONO (4639 1675);
FORCEPROP 2 LAST CDS_LIB standard
J 0
(4450 1675);
DISPLAY INVISIBLE (4450 1675);
FORCEPROP 1 LAST OFFPAGE TRUE
J 0
(4775 1550);
DISPLAY 0.872340 (4775 1550);
PAINT GREEN (4775 1550);
DISPLAY INVISIBLE (4775 1550);
FORCEPROP 1 LAST COMMENT_BODY TRUE
J 0
(4405 1580);
DISPLAY 0.872340 (4405 1580);
PAINT PEACH (4405 1580);
DISPLAY INVISIBLE (4405 1580);
FORCEPROP 2 LAST PATH I76
J 0
(4650 1725);
DISPLAY 1.021277 (4650 1725);
DISPLAY INVISIBLE (4650 1725);
FORCEADD OFFPAGE..2
(4450 1725);
FORCEPROP 2 LAST $XR0 10 
J 0
(4639 1725);
DISPLAY 0.638298 (4639 1725);
PAINT MONO (4639 1725);
FORCEPROP 2 LAST CDS_LIB standard
J 0
(4450 1725);
DISPLAY INVISIBLE (4450 1725);
FORCEPROP 1 LAST OFFPAGE TRUE
J 0
(4775 1600);
DISPLAY 0.872340 (4775 1600);
PAINT GREEN (4775 1600);
DISPLAY INVISIBLE (4775 1600);
FORCEPROP 1 LAST COMMENT_BODY TRUE
J 0
(4405 1630);
DISPLAY 0.872340 (4405 1630);
PAINT PEACH (4405 1630);
DISPLAY INVISIBLE (4405 1630);
FORCEPROP 2 LAST PATH I77
J 0
(4650 1775);
DISPLAY 1.021277 (4650 1775);
DISPLAY INVISIBLE (4650 1775);
FORCEADD OFFPAGE..2
(4450 1775);
FORCEPROP 2 LAST $XR1 10 
J 0
(4729 1775);
DISPLAY 0.638298 (4729 1775);
PAINT MONO (4729 1775);
FORCEPROP 2 LAST $XR0 11 
J 0
(4639 1775);
DISPLAY 0.638298 (4639 1775);
PAINT MONO (4639 1775);
FORCEPROP 1 LAST COMMENT_BODY TRUE
J 0
(4405 1680);
DISPLAY 0.872340 (4405 1680);
PAINT PEACH (4405 1680);
DISPLAY INVISIBLE (4405 1680);
FORCEPROP 1 LAST OFFPAGE TRUE
J 0
(4775 1650);
DISPLAY 0.872340 (4775 1650);
PAINT GREEN (4775 1650);
DISPLAY INVISIBLE (4775 1650);
FORCEPROP 2 LAST PATH I78
J 0
(4650 1825);
DISPLAY 1.021277 (4650 1825);
DISPLAY INVISIBLE (4650 1825);
FORCEPROP 2 LAST CDS_LIB standard
J 0
(4450 1775);
DISPLAY INVISIBLE (4450 1775);
FORCEADD OFFPAGE..4
(3900 1975);
FORCEPROP 2 LAST $XR0 30 
J 0
(4086 1975);
DISPLAY 0.638298 (4086 1975);
PAINT MONO (4086 1975);
FORCEPROP 2 LAST CDS_LIB standard
J 0
(3900 1975);
DISPLAY INVISIBLE (3900 1975);
FORCEPROP 2 LAST PATH I79
J 0
(4100 2025);
DISPLAY 1.021277 (4100 2025);
DISPLAY INVISIBLE (4100 2025);
FORCEPROP 1 LAST OFFPAGE TRUE
J 0
(4225 1850);
DISPLAY 1.574468 (4225 1850);
PAINT GREEN (4225 1850);
DISPLAY INVISIBLE (4225 1850);
FORCEPROP 1 LAST COMMENT_BODY TRUE
J 0
(3875 1875);
DISPLAY 1.574468 (3875 1875);
PAINT PEACH (3875 1875);
DISPLAY INVISIBLE (3875 1875);
FORCEADD OFFPAGE..2
R 2
(-3425 2025);
FORCEPROP 2 LAST $XR0 10 
J 0
(-3679 2025);
DISPLAY 0.638298 (-3679 2025);
PAINT MONO (-3679 2025);
FORCEPROP 2 LAST PATH I8
J 0
(-3625 2075);
DISPLAY 1.021277 (-3625 2075);
DISPLAY INVISIBLE (-3625 2075);
FORCEPROP 1 LAST COMMENT_BODY TRUE
J 2
(-3380 1930);
DISPLAY 0.872340 (-3380 1930);
PAINT PEACH (-3380 1930);
DISPLAY INVISIBLE (-3380 1930);
FORCEPROP 1 LAST OFFPAGE TRUE
J 2
(-3750 1900);
DISPLAY 0.872340 (-3750 1900);
PAINT GREEN (-3750 1900);
DISPLAY INVISIBLE (-3750 1900);
FORCEPROP 2 LAST CDS_LIB standard
J 0
(-3425 2025);
DISPLAY INVISIBLE (-3425 2025);
FORCEADD OFFPAGE..2
(3900 2025);
FORCEPROP 2 LAST $XR0 27 
J 0
(4089 2025);
DISPLAY 0.638298 (4089 2025);
PAINT MONO (4089 2025);
FORCEPROP 2 LAST $XR1 30 
J 0
(4179 2025);
DISPLAY 0.638298 (4179 2025);
PAINT MONO (4179 2025);
FORCEPROP 2 LAST CDS_LIB standard
J 0
(3900 2025);
DISPLAY INVISIBLE (3900 2025);
FORCEPROP 2 LAST PATH I80
J 0
(4200 2075);
DISPLAY 1.021277 (4200 2075);
DISPLAY INVISIBLE (4200 2075);
FORCEPROP 1 LAST OFFPAGE TRUE
J 0
(4225 1900);
DISPLAY 0.872340 (4225 1900);
PAINT GREEN (4225 1900);
DISPLAY INVISIBLE (4225 1900);
FORCEPROP 1 LAST COMMENT_BODY TRUE
J 0
(3855 1930);
DISPLAY 0.872340 (3855 1930);
PAINT PEACH (3855 1930);
DISPLAY INVISIBLE (3855 1930);
FORCEADD Q_RES..1
(3650 3325);
FORCEPROP 1 LAST VALUE 33.2
J 1
(3800 3325);
DISPLAY 0.510638 (3800 3325);
PAINT SKYBLUE (3800 3325);
FORCEPROP 1 LAST MATERIAL CHIP
J 1
(3900 3325);
DISPLAY 0.510638 (3900 3325);
PAINT SKYBLUE (3900 3325);
FORCEPROP 2 LAST SEC_TYPE 0402LF
J 0
(3600 3525);
DISPLAY 0.680851 (3600 3525);
DISPLAY INVISIBLE (3600 3525);
FORCEPROP 2 LAST CDS_LIB pure_quanta
J 0
(3650 3325);
DISPLAY INVISIBLE (3650 3325);
FORCEPROP 1 LAST WATTAGE 1/16W
J 2
(3625 3175);
DISPLAY 0.510638 (3625 3175);
PAINT SKYBLUE (3625 3175);
DISPLAY INVISIBLE (3625 3175);
FORCEPROP 1 LAST PACK_TYPE 0402LF
J 0
(3900 3175);
DISPLAY 0.510638 (3900 3175);
PAINT SKYBLUE (3900 3175);
DISPLAY INVISIBLE (3900 3175);
FORCEPROP 1 LAST PART_NUMBER CS03322FB03
J 0
(3850 3225);
DISPLAY 0.510638 (3850 3225);
PAINT WHITE (3850 3225);
DISPLAY INVISIBLE (3850 3225);
FORCEPROP 1 LAST TOLERANCE 1%
J 0
(3775 3325);
DISPLAY 0.510638 (3775 3325);
PAINT SKYBLUE (3775 3325);
DISPLAY INVISIBLE (3775 3325);
FORCEPROP 1 LAST PATH I87
J 0
(3600 3475);
DISPLAY 0.978723 (3600 3475);
PAINT WHITE (3600 3475);
DISPLAY INVISIBLE (3600 3475);
FORCEPROP 1 LAST LOCATION R177
J 2
(3550 3325);
DISPLAY 0.702128 (3550 3325);
PAINT YELLOW (3550 3325);
FORCEPROP 1 LASTPIN (3550 3325) $PN 1
J 0
(3562 3337);
DISPLAY 0.808511 (3562 3337);
PAINT WHITE (3562 3337);
FORCEPROP 1 LASTPIN (3750 3325) $PN 2
J 0
(3712 3337);
DISPLAY 0.808511 (3712 3337);
PAINT WHITE (3712 3337);
FORCEPROP 0 LAST SEC 1
J 0
(3600 3425);
DISPLAY 0.680851 (3600 3425);
PAINT MONO (3600 3425);
DISPLAY INVISIBLE (3600 3425);
FORCEADD OFFPAGE..2
R 2
(-3425 2175);
FORCEPROP 2 LAST $XR0 30 
J 0
(-3679 2175);
DISPLAY 0.638298 (-3679 2175);
PAINT MONO (-3679 2175);
FORCEPROP 1 LAST OFFPAGE TRUE
J 2
(-3750 2050);
DISPLAY 0.872340 (-3750 2050);
PAINT GREEN (-3750 2050);
DISPLAY INVISIBLE (-3750 2050);
FORCEPROP 1 LAST COMMENT_BODY TRUE
J 2
(-3380 2080);
DISPLAY 0.872340 (-3380 2080);
PAINT PEACH (-3380 2080);
DISPLAY INVISIBLE (-3380 2080);
FORCEPROP 2 LAST PATH I9
J 0
(-3625 2225);
DISPLAY 1.021277 (-3625 2225);
DISPLAY INVISIBLE (-3625 2225);
FORCEPROP 2 LAST CDS_LIB standard
J 0
(-3425 2175);
DISPLAY INVISIBLE (-3425 2175);
FORCEADD OFFPAGE..2
(4925 3375);
FORCEPROP 2 LAST $XR0 36 
J 0
(5114 3375);
DISPLAY 0.638298 (5114 3375);
PAINT MONO (5114 3375);
FORCEPROP 2 LAST $XR1 48 
J 0
(5204 3375);
DISPLAY 0.638298 (5204 3375);
PAINT MONO (5204 3375);
FORCEPROP 2 LAST CDS_LIB standard
J 0
(4925 3375);
DISPLAY INVISIBLE (4925 3375);
FORCEPROP 2 LAST PATH I91
J 0
(5125 3425);
DISPLAY 1.021277 (5125 3425);
DISPLAY INVISIBLE (5125 3425);
FORCEPROP 1 LAST COMMENT_BODY TRUE
J 0
(4880 3280);
DISPLAY 0.872340 (4880 3280);
PAINT PEACH (4880 3280);
DISPLAY INVISIBLE (4880 3280);
FORCEPROP 1 LAST OFFPAGE TRUE
J 0
(5250 3250);
DISPLAY 0.872340 (5250 3250);
PAINT GREEN (5250 3250);
DISPLAY INVISIBLE (5250 3250);
FORCEADD Q_RES..1
(3350 4325);
FORCEPROP 1 LAST MATERIAL CHIP
J 0
(3550 4325);
DISPLAY 0.510638 (3550 4325);
PAINT SKYBLUE (3550 4325);
FORCEPROP 1 LAST VALUE 33.2
J 2
(3525 4325);
DISPLAY 0.510638 (3525 4325);
PAINT SKYBLUE (3525 4325);
FORCEPROP 1 LAST TOLERANCE 1%
J 0
(3275 4425);
DISPLAY 0.510638 (3275 4425);
PAINT SKYBLUE (3275 4425);
DISPLAY INVISIBLE (3275 4425);
FORCEPROP 1 LAST PART_NUMBER CS03322FB03
J 0
(3250 4400);
DISPLAY 0.510638 (3250 4400);
PAINT WHITE (3250 4400);
DISPLAY INVISIBLE (3250 4400);
FORCEPROP 1 LAST PACK_TYPE 0402LF
J 0
(3325 4375);
DISPLAY 0.510638 (3325 4375);
PAINT SKYBLUE (3325 4375);
DISPLAY INVISIBLE (3325 4375);
FORCEPROP 1 LAST WATTAGE 1/16W
J 2
(3700 4425);
DISPLAY 0.510638 (3700 4425);
PAINT SKYBLUE (3700 4425);
DISPLAY INVISIBLE (3700 4425);
FORCEPROP 1 LAST PATH I94
J 0
(3300 4475);
DISPLAY 0.978723 (3300 4475);
PAINT WHITE (3300 4475);
DISPLAY INVISIBLE (3300 4475);
FORCEPROP 2 LAST CDS_LIB pure_quanta
J 0
(3350 4325);
DISPLAY INVISIBLE (3350 4325);
FORCEPROP 1 LAST LOCATION R178
J 0
(3125 4325);
DISPLAY 0.702128 (3125 4325);
PAINT YELLOW (3125 4325);
FORCEPROP 0 LAST $SEC 1
J 0
(3125 4375);
DISPLAY 0.680851 (3125 4375);
PAINT MONO (3125 4375);
DISPLAY INVISIBLE (3125 4375);
FORCEPROP 0 LAST CDS_SEC 1
J 0
(3125 4375);
DISPLAY 1.021277 (3125 4375);
DISPLAY INVISIBLE (3125 4375);
FORCEPROP 1 LASTPIN (3250 4325) $PN 1
J 0
(3262 4337);
DISPLAY 0.808511 (3262 4337);
PAINT WHITE (3262 4337);
DISPLAY INVISIBLE (3262 4337);
FORCEPROP 1 LASTPIN (3450 4325) $PN 2
J 0
(3412 4337);
DISPLAY 0.808511 (3412 4337);
PAINT WHITE (3412 4337);
DISPLAY INVISIBLE (3412 4337);
FORCEADD Q_RES..1
(3350 4275);
FORCEPROP 1 LAST VALUE 33.2
J 2
(3525 4275);
DISPLAY 0.510638 (3525 4275);
PAINT SKYBLUE (3525 4275);
FORCEPROP 1 LAST MATERIAL CHIP
J 0
(3550 4275);
DISPLAY 0.510638 (3550 4275);
PAINT SKYBLUE (3550 4275);
FORCEPROP 1 LAST TOLERANCE 1%
J 0
(3275 4375);
DISPLAY 0.510638 (3275 4375);
PAINT SKYBLUE (3275 4375);
DISPLAY INVISIBLE (3275 4375);
FORCEPROP 1 LAST PART_NUMBER CS03322FB03
J 0
(3250 4350);
DISPLAY 0.510638 (3250 4350);
PAINT WHITE (3250 4350);
DISPLAY INVISIBLE (3250 4350);
FORCEPROP 1 LAST PACK_TYPE 0402LF
J 0
(3325 4325);
DISPLAY 0.510638 (3325 4325);
PAINT SKYBLUE (3325 4325);
DISPLAY INVISIBLE (3325 4325);
FORCEPROP 1 LAST WATTAGE 1/16W
J 2
(3700 4375);
DISPLAY 0.510638 (3700 4375);
PAINT SKYBLUE (3700 4375);
DISPLAY INVISIBLE (3700 4375);
FORCEPROP 1 LAST PATH I95
J 0
(3300 4425);
DISPLAY 0.978723 (3300 4425);
PAINT WHITE (3300 4425);
DISPLAY INVISIBLE (3300 4425);
FORCEPROP 2 LAST CDS_LIB pure_quanta
J 0
(3350 4275);
DISPLAY INVISIBLE (3350 4275);
FORCEPROP 1 LAST LOCATION R179
J 0
(3125 4275);
DISPLAY 0.702128 (3125 4275);
PAINT YELLOW (3125 4275);
FORCEPROP 0 LAST $SEC 1
J 0
(3125 4325);
DISPLAY 0.680851 (3125 4325);
PAINT MONO (3125 4325);
DISPLAY INVISIBLE (3125 4325);
FORCEPROP 0 LAST CDS_SEC 1
J 0
(3125 4325);
DISPLAY 1.021277 (3125 4325);
DISPLAY INVISIBLE (3125 4325);
FORCEPROP 1 LASTPIN (3250 4275) $PN 1
J 0
(3262 4287);
DISPLAY 0.808511 (3262 4287);
PAINT WHITE (3262 4287);
DISPLAY INVISIBLE (3262 4287);
FORCEPROP 1 LASTPIN (3450 4275) $PN 2
J 0
(3412 4287);
DISPLAY 0.808511 (3412 4287);
PAINT WHITE (3412 4287);
DISPLAY INVISIBLE (3412 4287);
FORCEADD Q_RES..1
(3350 4225);
FORCEPROP 1 LAST MATERIAL CHIP
J 0
(3550 4225);
DISPLAY 0.510638 (3550 4225);
PAINT SKYBLUE (3550 4225);
FORCEPROP 1 LAST VALUE 33.2
J 2
(3525 4225);
DISPLAY 0.510638 (3525 4225);
PAINT SKYBLUE (3525 4225);
FORCEPROP 1 LAST TOLERANCE 1%
J 0
(3275 4325);
DISPLAY 0.510638 (3275 4325);
PAINT SKYBLUE (3275 4325);
DISPLAY INVISIBLE (3275 4325);
FORCEPROP 1 LAST PART_NUMBER CS03322FB03
J 0
(3250 4300);
DISPLAY 0.510638 (3250 4300);
PAINT WHITE (3250 4300);
DISPLAY INVISIBLE (3250 4300);
FORCEPROP 1 LAST PACK_TYPE 0402LF
J 0
(3325 4275);
DISPLAY 0.510638 (3325 4275);
PAINT SKYBLUE (3325 4275);
DISPLAY INVISIBLE (3325 4275);
FORCEPROP 1 LAST WATTAGE 1/16W
J 2
(3700 4325);
DISPLAY 0.510638 (3700 4325);
PAINT SKYBLUE (3700 4325);
DISPLAY INVISIBLE (3700 4325);
FORCEPROP 1 LAST PATH I96
J 0
(3300 4375);
DISPLAY 0.978723 (3300 4375);
PAINT WHITE (3300 4375);
DISPLAY INVISIBLE (3300 4375);
FORCEPROP 2 LAST CDS_LIB pure_quanta
J 0
(3350 4225);
DISPLAY INVISIBLE (3350 4225);
FORCEPROP 1 LAST LOCATION R180
J 0
(3125 4225);
DISPLAY 0.702128 (3125 4225);
PAINT YELLOW (3125 4225);
FORCEPROP 0 LAST $SEC 1
J 0
(3125 4275);
DISPLAY 0.680851 (3125 4275);
PAINT MONO (3125 4275);
DISPLAY INVISIBLE (3125 4275);
FORCEPROP 0 LAST CDS_SEC 1
J 0
(3125 4275);
DISPLAY 1.021277 (3125 4275);
DISPLAY INVISIBLE (3125 4275);
FORCEPROP 1 LASTPIN (3250 4225) $PN 1
J 0
(3262 4237);
DISPLAY 0.808511 (3262 4237);
PAINT WHITE (3262 4237);
DISPLAY INVISIBLE (3262 4237);
FORCEPROP 1 LASTPIN (3450 4225) $PN 2
J 0
(3412 4237);
DISPLAY 0.808511 (3412 4237);
PAINT WHITE (3412 4237);
DISPLAY INVISIBLE (3412 4237);
FORCEADD OFFPAGE..4
(4925 3325);
FORCEPROP 2 LAST $XR0 34 
J 0
(5111 3325);
DISPLAY 0.638298 (5111 3325);
PAINT MONO (5111 3325);
FORCEPROP 2 LAST PATH I97
J 0
(5125 3375);
DISPLAY 1.021277 (5125 3375);
DISPLAY INVISIBLE (5125 3375);
FORCEPROP 1 LAST COMMENT_BODY TRUE
J 0
(4900 3225);
DISPLAY 0.872340 (4900 3225);
PAINT PEACH (4900 3225);
DISPLAY INVISIBLE (4900 3225);
FORCEPROP 1 LAST OFFPAGE TRUE
J 0
(5250 3200);
DISPLAY 0.872340 (5250 3200);
PAINT GREEN (5250 3200);
DISPLAY INVISIBLE (5250 3200);
FORCEPROP 2 LAST CDS_LIB standard
J 0
(4925 3325);
DISPLAY INVISIBLE (4925 3325);
FORCEADD QUANTA_TITLE_BLOCK_C..1
(5300 -1325);
FORCEPROP 0 LAST CDS_CON_LAST_MODIFIED Fri Aug 25 17:25:36 2023
J 0
(3415 -1310);
DISPLAY INVISIBLE (3415 -1310);
FORCEPROP 2 LAST Q_DEPT 
J 1
(1537 -1276);
DISPLAY 1.957447 (1537 -1276);
PAINT GREEN (1537 -1276);
FORCEPROP 1 LAST CUSTOM_TXT_CDS <CON_LAST_MODIFIED>
J 0
(3415 -1310);
DISPLAY 0.978723 (3415 -1310);
FORCEPROP 2 LAST CUSTOM_TXT_CDS <XR_PAGE_TITLE>
J 0
(-2590 3925);
DISPLAY 0.638298 (-2590 3925);
PAINT PINK (-2590 3925);
DISPLAY INVISIBLE (-2590 3925);
FORCEPROP 1 LAST CUSTOM_TXT_CDS <NAME_2>
J 0
(2125 -1275);
FORCEPROP 1 LAST CUSTOM_TXT_CDS <NAME_1>
J 0
(2125 -1150);
FORCEPROP 1 LAST CUSTOM_TXT_CDS <Q_NUMBER>
J 0
(3897 -1222);
DISPLAY 1.212766 (3897 -1222);
FORCEPROP 1 LAST CUSTOM_TXT_CDS <Q_PROJ>
J 0
(2918 -1223);
DISPLAY 1.212766 (2918 -1223);
FORCEPROP 1 LAST CUSTOM_TXT_CDS <Q_REV>
J 0
(5116 -1222);
DISPLAY 1.212766 (5116 -1222);
FORCEPROP 1 LAST CUSTOM_TXT_CDS <CON_PAGE_NUM> OF <CON_TOTAL_PAGES>
J 0
(4854 -1307);
DISPLAY 0.978723 (4854 -1307);
FORCEPROP 1 LAST Q_TITLE BMC 2
J 0
(-4066 -1299);
DISPLAY 2.446809 (-4066 -1299);
PAINT GREEN (-4066 -1299);
FORCEPROP 1 LAST COMMENT_BODY TRUE
J 0
(5312 -1338);
DISPLAY 0.978723 (5312 -1338);
PAINT PEACH (5312 -1338);
DISPLAY INVISIBLE (5312 -1338);
FORCEPROP 1 LAST CDS_LMAN_SYM_OUTLINE -9475,6775,100,-125
J 0
(5300 -1325);
DISPLAY 0.468085 (5300 -1325);
PAINT GREEN (5300 -1325);
DISPLAY INVISIBLE (5300 -1325);
FORCEPROP 2 LAST CDS_LIB pure_quanta
J 0
(5300 -1325);
DISPLAY INVISIBLE (5300 -1325);
FORCEPROP 2 LAST PAGE_BORDER TRUE
J 0
(-2590 3925);
DISPLAY 0.638298 (-2590 3925);
PAINT PINK (-2590 3925);
DISPLAY INVISIBLE (-2590 3925);
FORCEPROP 2 LAST CDS_XR_PAGE_TITLE CR-13 : @SCM_LIB.SCM(SCH_1):PAGE13
J 0
(-2590 3925);
DISPLAY 0.638298 (-2590 3925);
PAINT PINK (-2590 3925);
DISPLAY INVISIBLE (-2590 3925);
FORCEADD BOM_NOTE..1
(2050 5050);
FORCEPROP 0 LAST L2 R468 CHANGE TO CS09092FB03
J 0
(1900 4925);
DISPLAY 1.021277 (1900 4925);
PAINT GREEN (1900 4925);
FORCEPROP 2 LAST CDS_LIB logical_power
J 0
(2050 5050);
DISPLAY INVISIBLE (2050 5050);
FORCEPROP 1 LAST COMMENT_BODY TRUE
J 0
(2075 5150);
DISPLAY 0.978723 (2075 5150);
PAINT PEACH (2075 5150);
DISPLAY INVISIBLE (2075 5150);
FORCEADD DNS..2
(3350 4725);
PAINT RED (3350 4725);
FORCEPROP 1 LAST COMMENT_BODY TRUE
R 1
J 0
(3425 4500);
DISPLAY 0.872340 (3425 4500);
PAINT PEACH (3425 4500);
DISPLAY INVISIBLE (3425 4500);
FORCEPROP 2 LAST CDS_LIB mstr_misc
J 0
(3350 4725);
DISPLAY INVISIBLE (3350 4725);
FORCEADD DNS..2
(3350 4575);
PAINT RED (3350 4575);
FORCEPROP 1 LAST COMMENT_BODY TRUE
R 1
J 0
(3425 4350);
DISPLAY 0.872340 (3425 4350);
PAINT PEACH (3425 4350);
DISPLAY INVISIBLE (3425 4350);
FORCEPROP 2 LAST CDS_LIB mstr_misc
J 0
(3350 4575);
DISPLAY INVISIBLE (3350 4575);
FORCEADD DNS..2
(3350 4675);
PAINT RED (3350 4675);
FORCEPROP 1 LAST COMMENT_BODY TRUE
R 1
J 0
(3425 4450);
DISPLAY 0.872340 (3425 4450);
PAINT PEACH (3425 4450);
DISPLAY INVISIBLE (3425 4450);
FORCEPROP 2 LAST CDS_LIB mstr_misc
J 0
(3350 4675);
DISPLAY INVISIBLE (3350 4675);
FORCEADD DNS..1
(-2875 -625);
PAINT RED (-2875 -625);
FORCEPROP 1 LAST COMMENT_BODY TRUE
R 1
J 0
(-2800 -850);
DISPLAY 0.872340 (-2800 -850);
PAINT PEACH (-2800 -850);
DISPLAY INVISIBLE (-2800 -850);
FORCEPROP 2 LAST CDS_LIB mstr_misc
J 0
(-2875 -625);
DISPLAY INVISIBLE (-2875 -625);
FORCEADD DNS..1
(-2800 -275);
PAINT RED (-2800 -275);
FORCEPROP 1 LAST COMMENT_BODY TRUE
R 1
J 0
(-2725 -500);
DISPLAY 0.872340 (-2725 -500);
PAINT PEACH (-2725 -500);
DISPLAY INVISIBLE (-2725 -500);
FORCEPROP 2 LAST CDS_LIB mstr_misc
J 0
(-2800 -275);
DISPLAY INVISIBLE (-2800 -275);
FORCEADD DNS..2
(3350 4525);
PAINT RED (3350 4525);
FORCEPROP 1 LAST COMMENT_BODY TRUE
R 1
J 0
(3425 4300);
DISPLAY 0.872340 (3425 4300);
PAINT PEACH (3425 4300);
DISPLAY INVISIBLE (3425 4300);
FORCEPROP 2 LAST CDS_LIB mstr_misc
J 0
(3350 4525);
DISPLAY INVISIBLE (3350 4525);
FORCEADD DNS..2
(3350 4625);
PAINT RED (3350 4625);
FORCEPROP 1 LAST COMMENT_BODY TRUE
R 1
J 0
(3425 4400);
DISPLAY 0.872340 (3425 4400);
PAINT PEACH (3425 4400);
DISPLAY INVISIBLE (3425 4400);
FORCEPROP 2 LAST CDS_LIB mstr_misc
J 0
(3350 4625);
DISPLAY INVISIBLE (3350 4625);
FORCEADD DNS..2
(2775 -100);
PAINT RED (2775 -100);
FORCEPROP 1 LAST COMMENT_BODY TRUE
R 1
J 0
(2850 -325);
DISPLAY 0.872340 (2850 -325);
PAINT PEACH (2850 -325);
DISPLAY INVISIBLE (2850 -325);
FORCEPROP 2 LAST CDS_LIB mstr_misc
J 0
(2775 -100);
DISPLAY INVISIBLE (2775 -100);
FORCEADD DNS..2
(-2175 1400);
PAINT RED (-2175 1400);
FORCEPROP 2 LAST CDS_LIB mstr_misc
J 0
(-2175 1400);
DISPLAY INVISIBLE (-2175 1400);
FORCEPROP 1 LAST COMMENT_BODY TRUE
R 1
J 0
(-2100 1175);
DISPLAY 0.872340 (-2100 1175);
PAINT PEACH (-2100 1175);
DISPLAY INVISIBLE (-2100 1175);
WIRE 16 -1 (-575 -525)(-575 -425);
WIRE 16 -1 (-425 -525)(-575 -525);
WIRE 16 -1 (-1225 0)(-1225 200);
WIRE 16 -1 (-1225 0)(-1350 0);
WIRE 16 -1 (-3175 0)(-3175 200);
WIRE 16 -1 (-2900 0)(-3175 0);
WIRE 16 -1 (-3375 -200)(-3375 -300);
WIRE 16 -1 (-3450 -550)(-3450 -650);
WIRE 16 -1 (-1175 5150)(-1600 5150);
WIRE 16 -1 (-1175 5125)(-1175 5150);
WIRE 16 -1 (-1600 5150)(-1600 4875);
WIRE 16 -1 (2475 -450)(2475 -600);
WIRE 16 -1 (2425 575)(2425 450);
WIRE 16 -1 (1050 -50)(1050 50);
WIRE 16 -1 (1200 -50)(1050 -50);
WIRE 16 -1 (-2400 975)(-2400 1025);
WIRE 16 -1 (-1650 -325)(-1650 -375);
WIRE 16 -1 (-1650 -325)(-1550 -325);
WIRE 16 -1 (-1750 -325)(-1650 -325);
WIRE 16 -1 (-1175 4900)(-1175 4925);
WIRE 16 -1 (-2325 4600)(-2325 4675);
WIRE 16 3135 (-1050 575)(-1050 -800);
WIRE 16 3135 (-1050 575)(-3650 575);
WIRE 16 3135 (-3650 -800)(-1050 -800);
WIRE 16 3135 (-3650 -800)(-3650 575);
WIRE 16 -1 (-2175 1025)(-450 1025);
FORCEPROP 2 LAST SIG_NAME PD_CLK_125M_PHY_BMC_RGMII
J 0
(-1735 1035);
DISPLAY 0.808511 (-1735 1035);
PAINT GREEN (-1735 1035);
WIRE 16 -1 (-3375 1275)(-450 1275);
FORCEPROP 2 LAST SIG_NAME CLK_BUF1_GPU_FPGA_OE_R_N
J 0
(-3360 1285);
DISPLAY 0.808511 (-3360 1285);
WIRE 16 -1 (-2400 1025)(-2375 1025);
WIRE 16 -1 (-2700 -300)(-2225 -300);
WIRE 16 -1 (-2775 -650)(-2100 -650);
WIRE 16 -1 (-2225 -300)(-2225 0);
WIRE 16 -1 (-2225 0)(-2700 0);
WIRE 16 -1 (-2100 0)(-2225 0);
WIRE 16 -1 (-2100 -650)(-2100 0);
WIRE 16 -1 (-1950 0)(-2100 0);
WIRE 16 -1 (-1950 0)(-1950 -50);
WIRE 16 -1 (-1750 0)(-1950 0);
WIRE 16 -1 (-1750 0)(-1750 -50);
WIRE 16 -1 (-1550 0)(-1750 0);
WIRE 16 -1 (-1550 0)(-1550 -50);
WIRE 16 -1 (-1350 0)(-1550 0);
WIRE 16 -1 (-1350 0)(-1350 -50);
WIRE 16 3135 (-775 -650)(-775 375);
WIRE 16 3135 (-775 -650)(2200 -650);
WIRE 16 3135 (2200 375)(-775 375);
WIRE 16 3135 (2200 375)(2200 -650);
WIRE 16 -1 (-450 1225)(-2100 1225);
FORCEPROP 2 LAST SIG_NAME FM_BIC_DEBUG_SW_N_R
J 0
(-1835 1235);
DISPLAY 0.851064 (-1835 1235);
WIRE 16 -1 (-3375 1325)(-450 1325);
FORCEPROP 2 LAST SIG_NAME GPU_FPGA_RST_N
J 0
(-3360 1335);
DISPLAY 0.808511 (-3360 1335);
WIRE 16 -1 (-450 1425)(-3375 1425);
FORCEPROP 2 LAST SIG_NAME FM_JTAG_SEL
J 2
(-2910 1435);
DISPLAY 0.808511 (-2910 1435);
WIRE 16 -1 (-2075 1625)(-450 1625);
FORCEPROP 2 LAST SIG_NAME RMII_CSRDV
J 0
(-1985 1635);
DISPLAY 0.808511 (-1985 1635);
WIRE 16 -1 (-2075 1675)(-450 1675);
FORCEPROP 2 LAST SIG_NAME RMII_RXD1
J 0
(-1985 1685);
DISPLAY 0.808511 (-1985 1685);
WIRE 16 -1 (-450 1775)(-2100 1775);
FORCEPROP 2 LAST SIG_NAME FM_PLT_BMC_THERMTRIP_N_R
J 2
(-800 1785);
DISPLAY 0.808511 (-800 1785);
WIRE 16 -1 (-2025 2125)(-450 2125);
FORCEPROP 2 LAST SIG_NAME UART_BMC_1_RXD
J 2
(-825 2135);
DISPLAY 0.808511 (-825 2135);
WIRE 16 -1 (-2025 2175)(-450 2175);
FORCEPROP 2 LAST SIG_NAME UART_BMC_1_TXD
J 2
(-825 2185);
DISPLAY 0.808511 (-825 2185);
WIRE 16 -1 (-2025 2225)(-450 2225);
FORCEPROP 0 LAST SIG_NAME FM_DBP_BMC_PRDY_R_N
J 2
(-985 2235);
DISPLAY 0.808511 (-985 2235);
WIRE 16 -1 (-450 2375)(-2200 2375);
FORCEPROP 2 LAST SIG_NAME PWRGD_PSU_AC_PWROK_BMC
J 0
(-1710 2385);
DISPLAY 0.808511 (-1710 2385);
WIRE 16 -1 (-2325 4675)(-2225 4675);
WIRE 16 -1 (-2975 -650)(-3450 -650);
WIRE 16 -1 (2650 450)(2425 450);
WIRE 16 -1 (2425 450)(2425 375);
WIRE 16 -1 (2650 375)(2425 375);
WIRE 16 -1 (2425 375)(2425 325);
WIRE 16 -1 (2650 325)(2425 325);
WIRE 16 -1 (2425 325)(2425 275);
WIRE 16 -1 (2650 275)(2425 275);
WIRE 16 -1 (2425 275)(2425 225);
WIRE 16 -1 (2650 225)(2425 225);
WIRE 16 -1 (2425 225)(2425 175);
WIRE 16 -1 (2425 175)(2650 175);
WIRE 16 -1 (2425 175)(2425 75);
WIRE 16 -1 (2425 75)(2650 75);
WIRE 16 -1 (2425 25)(2425 75);
WIRE 16 -1 (2425 25)(2650 25);
WIRE 16 -1 (2425 -25)(2650 -25);
WIRE 16 -1 (2425 25)(2425 -25);
WIRE 16 -1 (2425 -25)(2425 -75);
WIRE 16 -1 (2425 -75)(2650 -75);
WIRE 16 -1 (-2900 -300)(-3375 -300);
WIRE 16 -1 (-1950 -250)(-1950 -325);
WIRE 16 -1 (-1950 -325)(-1750 -325);
WIRE 16 -1 (-1750 -325)(-1750 -250);
WIRE 16 -1 (-1550 -250)(-1550 -325);
WIRE 16 -1 (-1550 -325)(-1350 -325);
WIRE 16 -1 (-1350 -325)(-1350 -250);
WIRE 16 -1 (2700 -600)(2475 -600);
WIRE 16 -1 (2475 -600)(2475 -650);
WIRE 16 -1 (2700 -650)(2475 -650);
WIRE 16 -1 (2475 -850)(2475 -650);
WIRE 16 -1 (2700 -850)(2475 -850);
WIRE 16 -1 (2475 -900)(2475 -850);
WIRE 16 -1 (2700 -900)(2475 -900);
WIRE 16 -1 (-1600 4875)(-1625 4875);
WIRE 16 -1 (1900 2375)(2950 2375);
FORCEPROP 2 LAST SIG_NAME LED_POSTCODE_2
J 2
(2875 2385);
DISPLAY 0.808511 (2875 2385);
WIRE 16 -1 (1900 2325)(2950 2325);
FORCEPROP 2 LAST SIG_NAME LED_POSTCODE_3
J 2
(2875 2335);
DISPLAY 0.808511 (2875 2335);
WIRE 16 -1 (2975 1975)(3850 1975);
FORCEPROP 2 LAST SIG_NAME UART_BMC_5_RXD_R
J 2
(3825 1985);
DISPLAY 0.808511 (3825 1985);
WIRE 16 -1 (2975 2025)(3850 2025);
FORCEPROP 2 LAST SIG_NAME UART_BMC_5_TXD_R
J 2
(3825 2035);
DISPLAY 0.808511 (3825 2035);
WIRE 16 -1 (1900 1825)(4400 1825);
FORCEPROP 2 LAST SIG_NAME IRQ_SML0_ALERT_R_N
J 0
(3665 1835);
DISPLAY 0.808511 (3665 1835);
WIRE 16 -1 (3050 1775)(1900 1775);
FORCEPROP 2 LAST SIG_NAME RMII_TXEN_R
J 0
(2065 1775);
DISPLAY 0.808511 (2065 1775);
WIRE 16 -1 (3050 1725)(1900 1725);
FORCEPROP 2 LAST SIG_NAME RMII_TXD0_R
J 0
(2065 1725);
DISPLAY 0.808511 (2065 1725);
WIRE 16 -1 (3050 1675)(1900 1675);
FORCEPROP 2 LAST SIG_NAME RMII_TXD1_R
J 0
(2065 1675);
DISPLAY 0.808511 (2065 1675);
WIRE 16 -1 (1900 1575)(2875 1575);
FORCEPROP 2 LAST SIG_NAME FM_BIOS_DEBUG_EN_R_N
J 0
(2065 1585);
DISPLAY 0.851064 (2065 1585);
WIRE 16 -1 (2875 1575)(3050 1575);
WIRE 16 -1 (2875 1500)(2875 1575);
WIRE 16 -1 (3025 1500)(2875 1500);
WIRE 16 -1 (1900 1425)(4900 1425);
FORCEPROP 2 LAST SIG_NAME RST_PLTRST_R_N
J 0
(4165 1435);
DISPLAY 0.808511 (4165 1435);
WIRE 16 -1 (3250 1575)(4400 1575);
FORCEPROP 2 LAST SIG_NAME FM_BIOS_DEBUG_EN_N
J 2
(4340 1585);
DISPLAY 0.851064 (4340 1585);
WIRE 16 -1 (3250 1625)(4400 1625);
FORCEPROP 2 LAST SIG_NAME PD_BIOS_MUX_EN_N
J 2
(4340 1635);
DISPLAY 0.808511 (4340 1635);
WIRE 16 -1 (3250 1675)(4400 1675);
FORCEPROP 2 LAST SIG_NAME RMII_TXD1
J 2
(4340 1685);
DISPLAY 0.808511 (4340 1685);
WIRE 16 -1 (3250 1725)(4400 1725);
FORCEPROP 2 LAST SIG_NAME RMII_TXD0
J 2
(4340 1735);
DISPLAY 0.808511 (4340 1735);
WIRE 16 -1 (3250 1775)(4400 1775);
FORCEPROP 2 LAST SIG_NAME RMII_TXEN
J 2
(4340 1785);
DISPLAY 0.808511 (4340 1785);
WIRE 16 -1 (1900 1375)(3175 1375);
FORCEPROP 2 LAST SIG_NAME FM_CPU_RMCA_CATERR_LVT3_R_N
J 0
(1990 1385);
DISPLAY 0.808511 (1990 1385);
WIRE 16 -1 (3175 1325)(1900 1325);
FORCEPROP 2 LAST SIG_NAME FM_BMC_CPU_FBRK_OUT_N
J 0
(2075 1335);
DISPLAY 0.808511 (2075 1335);
WIRE 16 -1 (3175 1275)(1900 1275);
FORCEPROP 2 LAST SIG_NAME RST_SGPIO_RESET_BMC_N
J 0
(2075 1285);
DISPLAY 0.808511 (2075 1285);
WIRE 2 -1 (3175 1225)(1900 1225);
FORCEPROP 2 LAST SIG_NAME RST_ROT_CPU_R1_N
J 0
(2065 1235);
DISPLAY 0.851064 (2065 1235);
WIRE 16 -1 (4900 1175)(1900 1175);
FORCEPROP 0 LAST SIG_NAME H_CPU_CATERR_LVC2_R2_N
J 2
(4715 1185);
DISPLAY 0.808511 (4715 1185);
WIRE 16 -1 (1900 1075)(4425 1075);
FORCEPROP 2 LAST SIG_NAME IRQ_BMC_PCH_NMI_N
J 0
(2065 1085);
DISPLAY 0.808511 (2065 1085);
WIRE 16 -1 (1900 1025)(4425 1025);
FORCEPROP 2 LAST SIG_NAME BMC_MONITER
J 0
(2065 1035);
DISPLAY 0.808511 (2065 1035);
WIRE 16 3135 (3200 1650)(3200 1800);
WIRE 16 3135 (3100 1650)(3200 1650);
WIRE 16 3135 (3200 1800)(3100 1800);
WIRE 16 3135 (3100 1800)(3100 1650);
WIRE 2 -1 (-1675 2775)(-450 2775);
FORCEPROP 2 LAST SIG_NAME BMC_ID_BEEP_SEL_R1
J 0
(-1435 2785);
DISPLAY 0.808511 (-1435 2785);
WIRE 16 -1 (-2075 2875)(-450 2875);
FORCEPROP 2 LAST SIG_NAME FM_SLPS3_GF_R1_N
J 0
(-1435 2885);
DISPLAY 0.808511 (-1435 2885);
WIRE 16 -1 (-1650 3025)(-450 3025);
FORCEPROP 2 LAST SIG_NAME IRQ_BMC_CPU_NMI
J 0
(-1460 3035);
DISPLAY 0.808511 (-1460 3035);
WIRE 16 -1 (-2925 3125)(-450 3125);
FORCEPROP 2 LAST SIG_NAME FM_ID_LED
J 0
(-2860 3135);
DISPLAY 0.808511 (-2860 3135);
WIRE 16 -1 (-450 3225)(-1650 3225);
FORCEPROP 2 LAST SIG_NAME SMB_BMC_ALERT4_R_N
J 0
(-1435 3235);
DISPLAY 0.808511 (-1435 3235);
WIRE 16 -1 (-450 3375)(-2925 3375);
FORCEPROP 2 LAST SIG_NAME FM_ME_BT_DONE
J 0
(-2850 3385);
DISPLAY 0.808511 (-2850 3385);
WIRE 16 -1 (-2925 3825)(-450 3825);
FORCEPROP 2 LAST SIG_NAME PU_SPI1WP_N
J 0
(-2900 3835);
DISPLAY 0.808511 (-2900 3835);
WIRE 16 -1 (3375 1375)(4900 1375);
FORCEPROP 2 LAST SIG_NAME FM_CPU_MSMI_CATERR_LVT3_N
J 2
(4700 1385);
DISPLAY 0.808511 (4700 1385);
WIRE 16 -1 (3375 1275)(4900 1275);
FORCEPROP 2 LAST SIG_NAME RST_SGPIO_RESET_N
J 2
(4715 1285);
DISPLAY 0.808511 (4715 1285);
WIRE 2 -1 (3375 1225)(4900 1225);
FORCEPROP 2 LAST SIG_NAME RST_ROT_CPU_N
J 0
(4190 1235);
DISPLAY 0.851064 (4190 1235);
WIRE 16 -1 (4050 275)(2850 275);
FORCEPROP 2 LAST SIG_NAME PU_FWSPIWP_N
J 2
(3990 285);
DISPLAY 0.808511 (3990 285);
WIRE 16 -1 (4050 325)(2850 325);
FORCEPROP 2 LAST SIG_NAME PU_BMC_FWSPIABR_N
J 2
(3990 335);
DISPLAY 0.808511 (3990 335);
WIRE 16 -1 (4050 375)(2850 375);
FORCEPROP 2 LAST SIG_NAME SPI_BMC_TPM_CS2_R_N
J 0
(3240 385);
DISPLAY 0.851064 (3240 385);
WIRE 16 -1 (4050 450)(2850 450);
FORCEPROP 2 LAST SIG_NAME IRQ_PCH_SCI_WHEA_N
J 2
(3990 460);
DISPLAY 0.808511 (3990 460);
WIRE 16 -1 (4050 -75)(2850 -75);
FORCEPROP 2 LAST SIG_NAME FM_BMC_ONCTL_R_N
J 2
(3990 -65);
DISPLAY 0.808511 (3990 -65);
WIRE 16 -1 (4050 175)(2850 175);
FORCEPROP 2 LAST SIG_NAME PU_SPI1WP_N
J 2
(3990 185);
DISPLAY 0.808511 (3990 185);
WIRE 16 -1 (4050 75)(2850 75);
FORCEPROP 2 LAST SIG_NAME FM_BMC_SUSACK_N
J 2
(3990 85);
DISPLAY 0.808511 (3990 85);
WIRE 16 -1 (4050 -25)(2850 -25);
FORCEPROP 2 LAST SIG_NAME FM_SLPS3_GF_N
J 2
(3990 -15);
DISPLAY 0.808511 (3990 -15);
WIRE 16 -1 (4050 25)(2850 25);
FORCEPROP 2 LAST SIG_NAME IRQ_BMC_PCH_NMI_N
J 2
(3990 35);
DISPLAY 0.808511 (3990 35);
WIRE 16 -1 (4900 1325)(3375 1325);
FORCEPROP 2 LAST SIG_NAME FM_BMC_CPU_FBRK_OUT_R_N
J 2
(4715 1335);
DISPLAY 0.808511 (4715 1335);
WIRE 16 -1 (4050 225)(2850 225);
FORCEPROP 2 LAST SIG_NAME PU_SPI1ABR
J 2
(3990 235);
DISPLAY 0.808511 (3990 235);
WIRE 16 -1 (1900 2825)(3525 2825);
FORCEPROP 2 LAST SIG_NAME FM_BMC_READY_R_PLD_N
J 0
(2140 2835);
DISPLAY 0.851064 (2140 2835);
WIRE 16 -1 (3525 2825)(3700 2825);
WIRE 16 -1 (3525 2475)(3525 2825);
WIRE 16 -1 (3850 2475)(3525 2475);
WIRE 16 -1 (3700 2575)(1900 2575);
FORCEPROP 0 LAST SIG_NAME IRQ_PCH_SCI_WHEA_R_N
J 2
(2890 2585);
DISPLAY 0.808511 (2890 2585);
WIRE 2 -1 (1900 2625)(3700 2625);
FORCEPROP 2 LAST SIG_NAME FLASH_WP_STATUS_R1
J 0
(2140 2635);
DISPLAY 0.808511 (2140 2635);
WIRE 16 -1 (4875 2725)(1900 2725);
FORCEPROP 0 LAST SIG_NAME IRQ_TPM_SPI_N
J 2
(4865 2735);
DISPLAY 0.808511 (4865 2735);
WIRE 16 -1 (1900 2775)(3700 2775);
FORCEPROP 2 LAST SIG_NAME FM_BMC_SUSACK_R1_N
J 2
(2815 2785);
DISPLAY 0.808511 (2815 2785);
WIRE 16 -1 (3750 3325)(4875 3325);
FORCEPROP 2 LAST SIG_NAME H_CPU1_PROCHOT_LVC1_R_N
J 2
(4875 3335);
DISPLAY 0.808511 (4875 3335);
WIRE 16 -1 (1900 3375)(4875 3375);
FORCEPROP 2 LAST SIG_NAME FM_BMC_DEBUG_SW_N
J 2
(4875 3385);
DISPLAY 0.808511 (4875 3385);
WIRE 16 -1 (-2925 3325)(-450 3325);
FORCEPROP 2 LAST SIG_NAME VOL_SEN_ALERT_R
J 0
(-2850 3335);
DISPLAY 0.808511 (-2850 3335);
WIRE 16 -1 (-450 2325)(-2200 2325);
FORCEPROP 2 LAST SIG_NAME FM_PECI_SEL_R_N
J 0
(-1710 2335);
DISPLAY 0.851064 (-1710 2335);
WIRE 16 -1 (-450 2425)(-2200 2425);
FORCEPROP 2 LAST SIG_NAME FM_VIRTUAL_RESEAT_BMC
J 0
(-1710 2435);
DISPLAY 0.808511 (-1710 2435);
WIRE 16 -1 (-450 2625)(-1725 2625);
FORCEPROP 2 LAST SIG_NAME FM_THROTTLE_N
J 0
(-1435 2635);
DISPLAY 0.808511 (-1435 2635);
WIRE 16 -1 (-450 2725)(-1725 2725);
FORCEPROP 2 LAST SIG_NAME FM_BMC_ONCTL_R_N
J 0
(-1435 2735);
DISPLAY 0.808511 (-1435 2735);
WIRE 16 -1 (-450 3075)(-1650 3075);
FORCEPROP 2 LAST SIG_NAME FM_ESPI_PLD_R1_EN
J 0
(-1435 3085);
DISPLAY 0.808511 (-1435 3085);
PAINT GREEN (-1435 3085);
WIRE 16 -1 (3075 4125)(1900 4125);
FORCEPROP 2 LAST SIG_NAME SPI_BMC_IO3_R
J 0
(2175 4135);
DISPLAY 0.808511 (2175 4135);
WIRE 16 -1 (3250 4550)(3075 4550);
WIRE 16 -1 (3075 4550)(3075 4125);
WIRE 16 -1 (3025 4175)(1900 4175);
FORCEPROP 2 LAST SIG_NAME SPI_BMC_IO2_R
J 0
(2175 4185);
DISPLAY 0.808511 (2175 4185);
WIRE 16 -1 (3250 4600)(3025 4600);
WIRE 16 -1 (3025 4600)(3025 4175);
WIRE 2 -1 (1900 3875)(3150 3875);
FORCEPROP 2 LAST SIG_NAME FM_DEBUG_PORT_PRSNT_R1_N
J 0
(2040 3885);
DISPLAY 0.851064 (2040 3885);
WIRE 16 -1 (1900 3725)(4425 3725);
FORCEPROP 2 LAST SIG_NAME SPI_BMC_BIOS_ROM_CLK
J 2
(4425 3735);
DISPLAY 0.808511 (4425 3735);
WIRE 16 -1 (1900 3675)(4425 3675);
FORCEPROP 2 LAST SIG_NAME SPI_BMC_BIOS_ROM_MOSI
J 2
(4425 3685);
DISPLAY 0.808511 (4425 3685);
WIRE 16 -1 (4425 3525)(1900 3525);
FORCEPROP 2 LAST SIG_NAME SPI_BMC_BIOS_ROM_IO3
J 2
(4425 3535);
DISPLAY 0.808511 (4425 3535);
WIRE 16 -1 (-2925 3175)(-450 3175);
FORCEPROP 2 LAST SIG_NAME FM_BMC_MUX_CS_SPI_SEL_0
J 0
(-2860 3185);
DISPLAY 0.808511 (-2860 3185);
WIRE 16 -1 (4425 3625)(1900 3625);
FORCEPROP 2 LAST SIG_NAME SPI_BMC_BIOS_ROM_MISO
J 2
(4425 3635);
DISPLAY 0.808511 (4425 3635);
WIRE 16 -1 (3550 3125)(1900 3125);
FORCEPROP 2 LAST SIG_NAME RST_WDTRST_PLD_R1_N
J 0
(2140 3135);
DISPLAY 0.851064 (2140 3135);
WIRE 16 -1 (1900 1625)(3050 1625);
FORCEPROP 2 LAST SIG_NAME PD_BIOS_MUX_EN_R_N
J 0
(2065 1635);
DISPLAY 0.808511 (2065 1635);
WIRE 16 -1 (1900 2125)(2950 2125);
FORCEPROP 2 LAST SIG_NAME LED_POSTCODE_7
J 2
(2875 2135);
DISPLAY 0.808511 (2875 2135);
WIRE 16 -1 (1900 2175)(2950 2175);
FORCEPROP 2 LAST SIG_NAME LED_POSTCODE_6
J 2
(2875 2185);
DISPLAY 0.808511 (2875 2185);
WIRE 16 -1 (1900 2225)(2950 2225);
FORCEPROP 2 LAST SIG_NAME LED_POSTCODE_5
J 2
(2875 2235);
DISPLAY 0.808511 (2875 2235);
WIRE 16 -1 (1900 2275)(2950 2275);
FORCEPROP 2 LAST SIG_NAME LED_POSTCODE_4
J 2
(2875 2285);
DISPLAY 0.808511 (2875 2285);
WIRE 16 -1 (1900 2875)(4875 2875);
FORCEPROP 2 LAST SIG_NAME BATTERY_DETECT
J 2
(4865 2885);
DISPLAY 0.808511 (4865 2885);
WIRE 2 -1 (3750 3025)(4875 3025);
FORCEPROP 2 LAST SIG_NAME BMC_EMMC_RST_N
J 0
(4140 3035);
DISPLAY 0.808511 (4140 3035);
WIRE 2 -1 (3750 3075)(4875 3075);
FORCEPROP 2 LAST SIG_NAME FM_FLASH_LATCH_N
J 0
(4065 3085);
DISPLAY 0.808511 (4065 3085);
WIRE 16 -1 (3750 3125)(4875 3125);
FORCEPROP 2 LAST SIG_NAME RST_WDTRST_PLD_N
J 0
(4040 3135);
DISPLAY 0.851064 (4040 3135);
WIRE 16 -1 (3750 3175)(4875 3175);
FORCEPROP 2 LAST SIG_NAME RST_BMC_SELF_HW
J 0
(4040 3185);
DISPLAY 0.851064 (4040 3185);
WIRE 16 -1 (3750 3225)(4875 3225);
FORCEPROP 2 LAST SIG_NAME BMC_CPLD_GPIO_2
J 2
(4875 3235);
DISPLAY 0.808511 (4875 3235);
WIRE 16 -1 (3750 3275)(4875 3275);
FORCEPROP 2 LAST SIG_NAME RST_PCA9548_SENSOR_N
J 2
(4875 3285);
DISPLAY 0.808511 (4875 3285);
WIRE 16 -1 (1900 2425)(2950 2425);
FORCEPROP 2 LAST SIG_NAME LED_POSTCODE_1
J 2
(2875 2435);
DISPLAY 0.808511 (2875 2435);
WIRE 16 -1 (1900 2475)(2950 2475);
FORCEPROP 2 LAST SIG_NAME LED_POSTCODE_0
J 2
(2875 2485);
DISPLAY 0.808511 (2875 2485);
WIRE 2 -1 (3550 3025)(1900 3025);
FORCEPROP 2 LAST SIG_NAME BMC_EMMC_RST_R_N
J 0
(2140 3035);
DISPLAY 0.808511 (2140 3035);
WIRE 2 -1 (1900 3075)(3550 3075);
FORCEPROP 2 LAST SIG_NAME FM_FLASH_LATCH_N_R1
J 0
(2140 3085);
DISPLAY 0.808511 (2140 3085);
WIRE 16 3135 (-400 5300)(-3750 5300);
WIRE 16 3135 (-400 5300)(-400 4400);
WIRE 16 3135 (-3750 4400)(-3750 5300);
WIRE 16 3135 (-3750 4400)(-400 4400);
WIRE 16 -1 (3250 4650)(2975 4650);
WIRE 16 -1 (2975 4225)(1900 4225);
FORCEPROP 2 LAST SIG_NAME SPI_BMC_MISO_IO1_R
J 0
(2175 4235);
DISPLAY 0.808511 (2175 4235);
WIRE 16 -1 (2975 4650)(2975 4225);
WIRE 16 -1 (3250 4225)(2975 4225);
WIRE 2 -1 (1900 4025)(3150 4025);
FORCEPROP 2 LAST SIG_NAME SPI_BMC_TPM_CLK_R1
J 0
(2165 4035);
DISPLAY 0.808511 (2165 4035);
WIRE 16 -1 (1900 3575)(4425 3575);
FORCEPROP 2 LAST SIG_NAME SPI_BMC_BIOS_ROM_IO2
J 2
(4425 3585);
DISPLAY 0.808511 (4425 3585);
WIRE 16 -1 (3550 3325)(1900 3325);
FORCEPROP 2 LAST SIG_NAME H_CPU1_PROCHOT_LVC1_N
J 0
(2140 3335);
DISPLAY 0.808511 (2140 3335);
WIRE 16 -1 (3550 3275)(1900 3275);
FORCEPROP 2 LAST SIG_NAME RST_PCA9548_SENSOR_R_N
J 0
(2140 3285);
DISPLAY 0.808511 (2140 3285);
WIRE 16 -1 (3550 3225)(1900 3225);
FORCEPROP 2 LAST SIG_NAME BMC_CPLD_GPIO_2_R1
J 0
(2140 3235);
DISPLAY 0.808511 (2140 3235);
WIRE 16 -1 (3450 4325)(4425 4325);
FORCEPROP 2 LAST SIG_NAME SPI_BMC_BOOT_CLK
J 2
(4425 4335);
DISPLAY 0.808511 (4425 4335);
WIRE 16 -1 (3250 4700)(2925 4700);
WIRE 16 -1 (2925 4275)(1900 4275);
FORCEPROP 2 LAST SIG_NAME SPI_BMC_MOSI_IO0_R
J 0
(2175 4285);
DISPLAY 0.808511 (2175 4285);
WIRE 16 -1 (2925 4700)(2925 4275);
WIRE 16 -1 (3250 4275)(2925 4275);
WIRE 2 -1 (1900 3975)(3150 3975);
FORCEPROP 2 LAST SIG_NAME SPI_BMC_TPM_MOSI_R1
J 0
(2165 3985);
DISPLAY 0.808511 (2165 3985);
WIRE 16 -1 (-1675 4125)(-450 4125);
FORCEPROP 2 LAST SIG_NAME PU_FWSPIWP_N_R
J 0
(-1510 4135);
DISPLAY 0.808511 (-1510 4135);
WIRE 16 -1 (-2925 4125)(-1875 4125);
FORCEPROP 2 LAST SIG_NAME PU_FWSPIWP_N
J 0
(-2900 4135);
DISPLAY 0.808511 (-2900 4135);
WIRE 16 -1 (-225 -525)(675 -525);
FORCEPROP 2 LAST SIG_NAME BMC_HEARTBEAT_R_N
J 0
(-85 -515);
DISPLAY 0.808511 (-85 -515);
WIRE 16 -1 (-3375 1375)(-2275 1375);
FORCEPROP 2 LAST SIG_NAME IRQ_SGPIO_N
J 0
(-3335 1385);
DISPLAY 0.808511 (-3335 1385);
WIRE 16 -1 (1900 3825)(4425 3825);
FORCEPROP 2 LAST SIG_NAME CLK_GEN2_BMC_RC_OE_N
J 0
(3540 3835);
DISPLAY 0.808511 (3540 3835);
WIRE 2 -1 (3350 3975)(4425 3975);
FORCEPROP 2 LAST SIG_NAME SPI_BMC_TPM_MOSI
J 0
(3665 3985);
DISPLAY 0.808511 (3665 3985);
WIRE 2 -1 (3350 4025)(4425 4025);
FORCEPROP 2 LAST SIG_NAME SPI_BMC_TPM_CLK
J 0
(3665 4035);
DISPLAY 0.808511 (3665 4035);
WIRE 16 3135 (3375 4050)(3125 4050);
WIRE 16 3135 (3375 4050)(3375 4000);
WIRE 16 3135 (3125 4000)(3125 4050);
WIRE 16 3135 (3125 4000)(3375 4000);
WIRE 16 -1 (3450 4275)(4425 4275);
FORCEPROP 2 LAST SIG_NAME SPI_BMC_BOOT_MOSI
J 2
(4425 4285);
DISPLAY 0.808511 (4425 4285);
WIRE 16 -1 (-3350 4775)(-3350 4725);
WIRE 16 -1 (-3350 4775)(-2225 4775);
FORCEPROP 2 LAST SIG_NAME RMII_OCP_RCLKI_ISO
J 0
(-3260 4785);
DISPLAY 0.851064 (-3260 4785);
WIRE 16 -1 (-2925 3025)(-1850 3025);
FORCEPROP 2 LAST SIG_NAME IRQ_BMC_CPU_NMI_R
J 0
(-2875 3035);
DISPLAY 0.808511 (-2875 3035);
WIRE 16 -1 (-450 3275)(-1650 3275);
FORCEPROP 2 LAST SIG_NAME SMB_BMC_ALERT3_R_N
J 0
(-1435 3285);
DISPLAY 0.808511 (-1435 3285);
WIRE 2 -1 (3350 3875)(4425 3875);
FORCEPROP 2 LAST SIG_NAME FM_DEBUG_PORT_PRSNT_N
J 0
(3565 3885);
DISPLAY 0.851064 (3565 3885);
WIRE 2 -1 (3350 3925)(4425 3925);
FORCEPROP 2 LAST SIG_NAME SPI_BMC_TPM_MISO
J 0
(3665 3935);
DISPLAY 0.808511 (3665 3935);
WIRE 16 -1 (3450 4550)(4425 4550);
FORCEPROP 2 LAST SIG_NAME QSPI_2_PLD_IO3
J 2
(4425 4560);
DISPLAY 0.808511 (4425 4560);
WIRE 16 -1 (3450 4600)(4425 4600);
FORCEPROP 2 LAST SIG_NAME QSPI_2_PLD_IO2
J 2
(4425 4610);
DISPLAY 0.808511 (4425 4610);
WIRE 16 -1 (3450 4750)(4425 4750);
FORCEPROP 2 LAST SIG_NAME QSPI_2_PLD_CLK
J 2
(4425 4760);
DISPLAY 0.808511 (4425 4760);
WIRE 16 -1 (-3375 1175)(-2300 1175);
FORCEPROP 2 LAST SIG_NAME FM_BMC_CRASHLOG_TRIG_N
J 0
(-3335 1185);
DISPLAY 0.851064 (-3335 1185);
WIRE 16 -1 (-3375 1225)(-2300 1225);
FORCEPROP 2 LAST SIG_NAME FM_BIC_DEBUG_SW_N
J 0
(-3335 1235);
DISPLAY 0.851064 (-3335 1235);
WIRE 16 -1 (-450 1375)(-2075 1375);
FORCEPROP 2 LAST SIG_NAME IRQ_SGPIO_BMC_N
J 2
(-1235 1385);
DISPLAY 0.808511 (-1235 1385);
WIRE 16 -1 (-2925 3875)(-450 3875);
FORCEPROP 2 LAST SIG_NAME PU_SPI1ABR
J 0
(-2900 3885);
DISPLAY 0.808511 (-2900 3885);
WIRE 16 -1 (-1875 4325)(-2925 4325);
FORCEPROP 2 LAST SIG_NAME SPI_BMC_BOOT_CS0_R_N
J 0
(-2900 4335);
DISPLAY 0.808511 (-2900 4335);
WIRE 16 -1 (-3225 4875)(-2225 4875);
FORCEPROP 2 LAST SIG_NAME RMII_OCP_RCLKI
J 0
(-3135 4885);
DISPLAY 0.808511 (-3135 4885);
WIRE 16 -1 (-1625 4725)(-775 4725);
FORCEPROP 2 LAST SIG_NAME PWRGD_P1V0_AUX_DELAY_R
J 0
(-1560 4735);
DISPLAY 0.808511 (-1560 4735);
WIRE 16 -1 (-1625 4475)(-775 4475);
FORCEPROP 2 LAST SIG_NAME PWRGD_P1V0_AUX_DELAY
J 0
(-1610 4485);
DISPLAY 0.851064 (-1610 4485);
WIRE 16 -1 (-775 4475)(-775 4525);
WIRE 16 -1 (-2925 4175)(-1875 4175);
FORCEPROP 2 LAST SIG_NAME PU_BMC_FWSPIABR_N
J 0
(-2900 4185);
DISPLAY 0.808511 (-2900 4185);
WIRE 2 -1 (-2925 3975)(-1875 3975);
FORCEPROP 2 LAST SIG_NAME SPI_BMC_TPM_CS2_R_N
J 0
(-2910 3985);
DISPLAY 0.808511 (-2910 3985);
WIRE 2 -1 (-2925 3675)(-1925 3675);
FORCEPROP 2 LAST SIG_NAME PWRGD_DSW_PWROK
J 0
(-2910 3685);
DISPLAY 0.851064 (-2910 3685);
WIRE 16 -1 (-1925 3625)(-2925 3625);
FORCEPROP 2 LAST SIG_NAME IRQ_SMI_ACTIVE_GF_N
J 0
(-2910 3635);
DISPLAY 0.808511 (-2910 3635);
WIRE 16 -1 (-2925 3275)(-1850 3275);
FORCEPROP 2 LAST SIG_NAME SMB_BMC_ALERT3_N
J 0
(-2860 3285);
DISPLAY 0.808511 (-2860 3285);
WIRE 16 -1 (-2925 3075)(-1850 3075);
FORCEPROP 2 LAST SIG_NAME FM_ESPI_PLD_EN
J 0
(-2860 3085);
DISPLAY 0.808511 (-2860 3085);
PAINT GREEN (-2860 3085);
WIRE 16 -1 (-450 2275)(-2200 2275);
FORCEPROP 2 LAST SIG_NAME PWRGD_SYS_PWROK_BMC
J 2
(-985 2285);
DISPLAY 0.808511 (-985 2285);
WIRE 16 -1 (-2025 2025)(-450 2025);
FORCEPROP 2 LAST SIG_NAME FM_DBP_CPU_PREQ_GF_N
J 2
(-935 2035);
DISPLAY 0.808511 (-935 2035);
WIRE 16 -1 (-2025 1975)(-450 1975);
FORCEPROP 2 LAST SIG_NAME FM_JTAG_TCK_MUX_BMC_SEL_R1
J 2
(-710 1985);
DISPLAY 0.808511 (-710 1985);
WIRE 16 -1 (-2075 1825)(-450 1825);
FORCEPROP 2 LAST SIG_NAME RMII_OCP_RCLKI_R_ISO
J 0
(-1985 1835);
DISPLAY 0.808511 (-1985 1835);
WIRE 16 -1 (-2075 1725)(-450 1725);
FORCEPROP 2 LAST SIG_NAME RMII_RXD0
J 0
(-1985 1735);
DISPLAY 0.808511 (-1985 1735);
WIRE 16 -1 (-2075 1575)(-450 1575);
FORCEPROP 2 LAST SIG_NAME RMII_RXER
J 0
(-1985 1585);
DISPLAY 0.808511 (-1985 1585);
WIRE 16 -1 (-450 1175)(-2100 1175);
FORCEPROP 2 LAST SIG_NAME FM_BMC_CRASHLOG_TRIG_R1_N
J 0
(-1835 1185);
DISPLAY 0.851064 (-1835 1185);
WIRE 16 -1 (-3375 2425)(-2400 2425);
FORCEPROP 2 LAST SIG_NAME FM_VIRTUAL_RESEAT
J 0
(-3335 2435);
DISPLAY 0.808511 (-3335 2435);
WIRE 2 -1 (-2925 2775)(-1875 2775);
FORCEPROP 2 LAST SIG_NAME BMC_ID_BEEP_SEL
J 0
(-2885 2785);
DISPLAY 0.808511 (-2885 2785);
WIRE 16 -1 (-2350 4475)(-3350 4475);
FORCEPROP 2 LAST SIG_NAME RMII_OCP_RCLKI_R_ISO
J 0
(-3135 4485);
DISPLAY 0.851064 (-3135 4485);
WIRE 16 -1 (-3350 4525)(-3350 4475);
WIRE 16 -1 (-1875 4275)(-2925 4275);
FORCEPROP 2 LAST SIG_NAME SPI_BMC_BOOT_CS1_R_N
J 0
(-2900 4285);
DISPLAY 0.808511 (-2900 4285);
WIRE 16 -1 (-1725 3625)(-450 3625);
FORCEPROP 2 LAST SIG_NAME IRQ_SMI_ACTIVE_BMC_N
J 0
(-1510 3635);
DISPLAY 0.808511 (-1510 3635);
WIRE 2 -1 (-1725 3675)(-450 3675);
FORCEPROP 2 LAST SIG_NAME PWRGD_DSW_PWROK_R1
J 0
(-1510 3685);
DISPLAY 0.851064 (-1510 3685);
WIRE 16 -1 (-450 3725)(-1725 3725);
FORCEPROP 2 LAST SIG_NAME SPI_BMC_BIOS_CS0_R1_N
J 0
(-1510 3735);
DISPLAY 0.808511 (-1510 3735);
WIRE 2 -1 (-1675 3975)(-450 3975);
FORCEPROP 2 LAST SIG_NAME SPI_BMC_TPM_CS2_R1_N
J 0
(-1510 3985);
DISPLAY 0.808511 (-1510 3985);
WIRE 2 -1 (-1675 4025)(-450 4025);
FORCEPROP 2 LAST SIG_NAME TP_BMC_SPICS0_N
J 0
(-1510 4035);
DISPLAY 0.808511 (-1510 4035);
WIRE 16 -1 (-1675 4275)(-450 4275);
FORCEPROP 2 LAST SIG_NAME SPI_BMC_BOOT_CS1_R1_N
J 0
(-1510 4285);
DISPLAY 0.808511 (-1510 4285);
WIRE 16 -1 (2875 4325)(1900 4325);
FORCEPROP 2 LAST SIG_NAME SPI_BMC_CLK_R
J 0
(2175 4335);
DISPLAY 0.808511 (2175 4335);
WIRE 16 -1 (3250 4325)(2875 4325);
WIRE 16 -1 (2875 4750)(2875 4325);
WIRE 16 -1 (3250 4750)(2875 4750);
WIRE 16 -1 (3450 4225)(4425 4225);
FORCEPROP 2 LAST SIG_NAME SPI_BMC_BOOT_MISO
J 2
(4425 4235);
DISPLAY 0.808511 (4425 4235);
WIRE 16 -1 (3450 4650)(4425 4650);
FORCEPROP 2 LAST SIG_NAME QSPI_2_PLD_IO1
J 2
(4425 4660);
DISPLAY 0.808511 (4425 4660);
WIRE 16 -1 (3450 4700)(4425 4700);
FORCEPROP 2 LAST SIG_NAME QSPI_2_PLD_IO0
J 2
(4425 4710);
DISPLAY 0.808511 (4425 4710);
WIRE 16 -1 (3900 2575)(4875 2575);
FORCEPROP 0 LAST SIG_NAME IRQ_PCH_SCI_WHEA_N
J 2
(4865 2585);
DISPLAY 0.808511 (4865 2585);
WIRE 2 -1 (3900 2625)(4875 2625);
FORCEPROP 2 LAST SIG_NAME FLASH_WP_STATUS
J 0
(4290 2635);
DISPLAY 0.808511 (4290 2635);
WIRE 16 -1 (3900 2775)(4875 2775);
FORCEPROP 2 LAST SIG_NAME FM_BMC_SUSACK_N
J 2
(4865 2785);
DISPLAY 0.808511 (4865 2785);
WIRE 16 -1 (3900 2825)(4875 2825);
FORCEPROP 2 LAST SIG_NAME FM_BMC_READY_PLD_N
J 2
(4865 2835);
DISPLAY 0.851064 (4865 2835);
WIRE 2 -1 (1900 3925)(3150 3925);
FORCEPROP 2 LAST SIG_NAME SPI_BMC_TPM_MISO_R1
J 0
(2165 3935);
DISPLAY 0.808511 (2165 3935);
WIRE 16 -1 (3550 3175)(1900 3175);
FORCEPROP 2 LAST SIG_NAME RST_BMC_SELF_HW_R1
J 0
(2140 3185);
DISPLAY 0.851064 (2140 3185);
WIRE 16 -1 (-1725 2475)(-450 2475);
FORCEPROP 2 LAST SIG_NAME H_CPU0_PROCHOT_LVC1_N
J 0
(-1700 2485);
DISPLAY 0.808511 (-1700 2485);
WIRE 16 -1 (-450 2825)(-1675 2825);
FORCEPROP 2 LAST SIG_NAME RST_RSMRST_R_N
J 0
(-1435 2835);
DISPLAY 0.808511 (-1435 2835);
WIRE 16 -1 (-1675 4325)(-450 4325);
FORCEPROP 2 LAST SIG_NAME SPI_BMC_BOOT_CS0_R1_N
J 0
(-1510 4335);
DISPLAY 0.808511 (-1510 4335);
WIRE 16 -1 (-1675 4225)(-450 4225);
FORCEPROP 2 LAST SIG_NAME TP_BMC_SPICS2_N
J 0
(-1510 4235);
DISPLAY 0.808511 (-1510 4235);
WIRE 16 -1 (-1675 4175)(-450 4175);
FORCEPROP 2 LAST SIG_NAME PU_BMC_FWSPIABR_N_R
J 0
(-1510 4185);
DISPLAY 0.808511 (-1510 4185);
WIRE 16 -1 (-2925 3225)(-1850 3225);
FORCEPROP 2 LAST SIG_NAME SMB_BMC_ALERT4_N
J 0
(-2860 3235);
DISPLAY 0.808511 (-2860 3235);
WIRE 16 -1 (-2275 2875)(-2925 2875);
FORCEPROP 2 LAST SIG_NAME FM_SLPS3_GF_N
J 0
(-2885 2885);
DISPLAY 0.808511 (-2885 2885);
WIRE 16 -1 (-1925 3725)(-2925 3725);
FORCEPROP 2 LAST SIG_NAME SPI_BMC_BIOS_CS0_N
J 0
(-2900 3735);
DISPLAY 0.808511 (-2900 3735);
WIRE 16 -1 (1900 1975)(2775 1975);
FORCEPROP 2 LAST SIG_NAME UART_BMC_5_RXD
J 0
(2025 1985);
DISPLAY 0.808511 (2025 1985);
WIRE 16 -1 (1900 2025)(2775 2025);
FORCEPROP 2 LAST SIG_NAME UART_BMC_5_TXD
J 0
(2025 2035);
DISPLAY 0.808511 (2025 2035);
WIRE 16 -1 (975 -525)(1750 -525);
FORCEPROP 2 LAST SIG_NAME BMC_HEARTBEAT_N
J 0
(1040 -515);
DISPLAY 0.808511 (1040 -515);
WIRE 16 -1 (1750 -525)(1900 -525);
WIRE 16 -1 (1750 -50)(1750 -525);
WIRE 16 -1 (1400 -50)(1750 -50);
WIRE 16 -1 (-2925 2825)(-1875 2825);
FORCEPROP 2 LAST SIG_NAME RST_RSMRST_N
J 0
(-2875 2835);
DISPLAY 0.808511 (-2875 2835);
WIRE 16 -1 (-2400 2375)(-3375 2375);
FORCEPROP 2 LAST SIG_NAME PWRGD_PSU_AC_PWROK
J 0
(-3335 2385);
DISPLAY 0.808511 (-3335 2385);
WIRE 16 -1 (-2400 2325)(-3375 2325);
FORCEPROP 2 LAST SIG_NAME FM_PECI_SEL_N
J 0
(-3335 2335);
DISPLAY 0.851064 (-3335 2335);
WIRE 16 -1 (-2400 2275)(-3375 2275);
FORCEPROP 2 LAST SIG_NAME PWRGD_SYS_PWROK
J 2
(-2760 2285);
DISPLAY 0.808511 (-2760 2285);
WIRE 16 -1 (-3375 2225)(-2225 2225);
FORCEPROP 2 LAST SIG_NAME FM_DBP_BMC_PRDY_N
J 0
(-3325 2235);
DISPLAY 0.808511 (-3325 2235);
WIRE 16 -1 (-3375 2175)(-2225 2175);
FORCEPROP 2 LAST SIG_NAME UART_BMC_1_TXD_R
J 0
(-3325 2185);
DISPLAY 0.808511 (-3325 2185);
WIRE 16 -1 (-3375 2125)(-2225 2125);
FORCEPROP 2 LAST SIG_NAME UART_BMC_1_RXD_R
J 0
(-3325 2135);
DISPLAY 0.808511 (-3325 2135);
WIRE 16 -1 (-3375 1975)(-2225 1975);
FORCEPROP 2 LAST SIG_NAME FM_JTAG_TCK_MUX_BMC_SEL
J 0
(-3325 1985);
DISPLAY 0.808511 (-3325 1985);
WIRE 16 -1 (-3375 1775)(-2300 1775);
FORCEPROP 2 LAST SIG_NAME FM_PCH_BMC_THERMTRIP_N
J 0
(-3350 1785);
DISPLAY 0.808511 (-3350 1785);
WIRE 16 -1 (-3375 2025)(-2225 2025);
FORCEPROP 2 LAST SIG_NAME FM_DBP_CPU_PREQ_GF_R_N
J 0
(-3325 2035);
DISPLAY 0.808511 (-3325 2035);
WIRE 16 -1 (4225 -600)(2900 -600);
FORCEPROP 2 LAST SIG_NAME FM_BMC_READY_R_PLD_N
J 0
(3315 -590);
DISPLAY 0.851064 (3315 -590);
WIRE 16 -1 (4225 -650)(2900 -650);
FORCEPROP 2 LAST SIG_NAME FM_BIOS_DEBUG_EN_R_N
J 0
(3315 -640);
DISPLAY 0.851064 (3315 -640);
WIRE 16 -1 (4225 -900)(2900 -900);
FORCEPROP 2 LAST SIG_NAME RST_WDTRST_PLD_N
J 0
(3315 -890);
DISPLAY 0.851064 (3315 -890);
WIRE 16 -1 (4225 -850)(2900 -850);
FORCEPROP 2 LAST SIG_NAME FM_PECI_SEL_N
J 0
(3315 -840);
DISPLAY 0.851064 (3315 -840);
DOT 1 (-2225 0);
DOT 1 (-1950 0);
DOT 1 (-2100 0);
DOT 1 (-1550 0);
DOT 1 (2425 -25);
DOT 1 (-1750 -325);
DOT 1 (3525 2825);
DOT 1 (1750 -525);
DOT 1 (2425 450);
DOT 1 (2425 325);
DOT 1 (2475 -650);
DOT 1 (2425 25);
DOT 1 (2425 75);
DOT 1 (-1650 -325);
DOT 1 (-1750 0);
DOT 1 (2425 275);
DOT 1 (2425 225);
DOT 1 (2475 -850);
DOT 1 (2475 -600);
DOT 1 (2425 375);
DOT 1 (2875 4325);
DOT 1 (2875 1575);
DOT 1 (2925 4275);
DOT 1 (2975 4225);
DOT 1 (2425 175);
DOT 1 (-1350 0);
DOT 1 (-1550 -325);
FORCENOTE
MAC3 & MAC4 I/O VOLTAGE SELECTION
(-2975 475) 0;
DISPLAY LEFT (-2975 475);
DISPLAY 1.021277 (-2975 475);
PAINT WHITE (-2975 475);
FORCENOTE
HEART BEATING LED
(-675 -175) 0;
DISPLAY LEFT (-675 -175);
DISPLAY 1.021277 (-675 -175);
PAINT WHITE (-675 -175);
FORCENOTE
CHANGE TO 22OHM_20221206
(2800 1900) 0;
DISPLAY LEFT (2800 1900);
DISPLAY 0.638298 (2800 1900);
PAINT WHITE (2800 1900);
FORCENOTE
ADD BUFFER_20220804
(-3725 5200) 0;
DISPLAY LEFT (-3725 5200);
DISPLAY 1.595745 (-3725 5200);
PAINT WHITE (-3725 5200);
QUIT
